%FSTAX23Y23*%
%MOIN*%
%SFA1B1*%

%IPPOS*%
%ADD13C,0.010000*%
%ADD17C,0.006000*%
%ADD19C,0.008000*%
%ADD21C,0.005000*%
%ADD24C,0.009000*%
%ADD26O,0.078740X0.023620*%
%ADD27R,0.039370X0.074800*%
%ADD28R,0.070870X0.074800*%
%ADD29R,0.055910X0.061020*%
%ADD30R,0.017720X0.054330*%
%ADD31R,0.064960X0.051180*%
%ADD32R,0.078740X0.098430*%
%ADD33R,0.019680X0.090550*%
%ADD34R,0.041340X0.039370*%
%ADD35R,0.086610X0.041340*%
%ADD36R,0.019680X0.035430*%
%ADD37O,0.057090X0.017720*%
%ADD38R,0.077560X0.022440*%
%ADD39R,0.025590X0.041340*%
%ADD40R,0.051180X0.074800*%
%ADD41R,0.039370X0.070870*%
%ADD42R,0.039370X0.090550*%
%ADD43R,0.041340X0.045280*%
%ADD44R,0.027560X0.045280*%
%ADD45R,0.053150X0.027560*%
%ADD46R,0.050000X0.200000*%
%ADD47R,0.057090X0.037400*%
%ADD48R,0.028350X0.039370*%
%ADD49R,0.025590X0.023620*%
%ADD50R,0.028000X0.165000*%
%ADD51R,0.028000X0.126000*%
%ADD52R,0.031500X0.066930*%
%ADD53R,0.070870X0.009840*%
%ADD54R,0.026570X0.009840*%
%ADD55R,0.009840X0.022640*%
%ADD56R,0.027560X0.035430*%
%ADD57R,0.038580X0.034250*%
%ADD58R,0.212600X0.114170*%
%ADD59R,0.165350X0.125980*%
%ADD60R,0.096460X0.124020*%
%ADD61R,0.033470X0.039370*%
%ADD62R,0.057090X0.045280*%
%ADD63R,0.037400X0.039370*%
%ADD64R,0.025200X0.026770*%
%ADD65R,0.010830X0.009840*%
%ADD66R,0.009840X0.010830*%
%ADD67R,0.061020X0.009840*%
%ADD68R,0.066930X0.053150*%
%ADD69R,0.009840X0.061020*%
%ADD70R,0.053150X0.066930*%
%ADD71R,0.045280X0.057090*%
%ADD72R,0.026770X0.025200*%
%ADD73R,0.039370X0.037400*%
%ADD74R,0.039370X0.033470*%
%ADD75R,0.039370X0.028350*%
%ADD76R,0.023620X0.025590*%
%ADD77R,0.082870X0.044090*%
%ADD78R,0.035430X0.027560*%
%ADD143C,0.120000*%
%ADD153C,0.020000*%
%ADD154R,0.110430X0.066930*%
%ADD155R,0.105320X0.067910*%
%ADD156C,0.031500*%
%ADD157C,0.065980*%
%ADD158C,0.061020*%
%ADD159R,0.061020X0.061020*%
%ADD160C,0.075000*%
%ADD161C,0.098430*%
%ADD162O,0.088580X0.177170*%
%ADD163O,0.177170X0.088580*%
%ADD164O,0.196850X0.098430*%
%ADD165C,0.112000*%
%ADD166C,0.021660*%
%ADD167C,0.055000*%
%ADD168R,0.055000X0.055000*%
%ADD169C,0.050000*%
%ADD170C,0.250000*%
%ADD171C,0.016000*%
%ADD172C,0.200000*%
%LNgrandmaster-1*%
%LPD*%
G36*
X07001Y035D02*
X0647D01*
Y03893*
X07001*
Y035*
G37*
G36*
X0462Y03246D02*
Y02826D01*
X04502Y02708*
X04355*
X04354Y02709*
X04353Y02713*
X04356Y02718*
X04358Y02725*
Y02749*
X04376*
Y02811*
X04303*
Y02749*
X04321*
Y02725*
X04322Y02718*
X04326Y02713*
X04325Y02709*
X04324Y02708*
X0425*
X04249Y02709*
X04248Y02713*
X04251Y02718*
X04253Y02725*
Y02749*
X04271*
Y02811*
X04212*
X0421Y02816*
X04214Y0282*
X04222*
X04223Y0282*
X04271*
Y02833*
X04303*
Y0282*
X04376*
Y02833*
X04384*
X04388Y02829*
X04394Y02825*
X04401Y02823*
X04404*
X04407Y0282*
Y02817*
Y02812*
Y02764*
X04462*
Y02771*
X04503*
X0451Y02772*
X04516Y02776*
X0452Y02782*
X04522Y02789*
X0452Y02796*
X04516Y02802*
X0451Y02806*
X04503Y02808*
X04465*
X04462Y02811*
Y02815*
Y0282*
Y02867*
X04407*
X04402Y02865*
X04398Y02868*
X04391Y02869*
X04376*
Y02882*
X04303*
Y02869*
X04271*
Y02882*
X04198*
Y02854*
X04193Y02851*
X04174Y02833*
X0417Y02827*
X04169Y0282*
Y02815*
X04122*
Y02764*
X04177*
Y02771*
X04183Y02773*
X04189Y02777*
X04193Y02781*
X04198Y02779*
Y02749*
X04216*
Y02725*
X04217Y02718*
X04221Y02713*
X0422Y02709*
X04219Y02708*
X0408*
X04078Y02713*
X04079Y02715*
X04081Y02722*
X04079Y02728*
X04078Y02731*
Y02749*
X04101*
Y02811*
X04028*
Y02749*
X04051*
Y02731*
X04049Y02728*
X04048Y02722*
X04049Y02715*
X04051Y02713*
X04048Y02708*
X03974*
X03973Y0271*
X03972Y02713*
X03975Y02717*
X03977Y02724*
X03975Y0273*
X03973Y02734*
Y02749*
X03996*
Y02811*
X03923*
Y02749*
X03946*
Y02731*
X03945Y0273*
X03944Y02724*
X03945Y02717*
X03948Y02713*
X03948Y0271*
X03946Y02708*
X036*
Y0287*
X03599Y02874*
X03597Y02878*
X03578Y02897*
X03574Y029*
X03569Y02901*
X03559*
Y02921*
Y02922*
Y02926*
Y02927*
Y02968*
Y0297*
Y02973*
Y02975*
Y02984*
X0356Y02985*
X03559Y02987*
Y03017*
X03509*
X03506Y03021*
Y03022*
Y03082*
X03497*
Y03087*
X03498Y03087*
X03503Y03091*
X03506Y03096*
X03508Y03103*
X03506Y03109*
X03503Y03114*
X03498Y03118*
X03491Y03119*
X03485Y03118*
X0348Y03114*
X03479Y03113*
X0331*
X03305Y03112*
X03301Y0311*
X03242Y0305*
X03239Y03047*
X03238Y03042*
Y02988*
X03218Y02968*
X03216Y02969*
X03214Y0297*
X03212Y02976*
X03209Y02981*
X03204Y02985*
X03197Y02986*
X03191Y02985*
X03186Y02981*
X03182Y02976*
X03181Y0297*
X03182Y02963*
X03186Y02958*
X03191Y02954*
X03197Y02953*
X03198Y02951*
X03199Y02948*
X03183Y02932*
X0318Y02928*
X03179Y02924*
Y02824*
X0318Y0282*
X03183Y02816*
X03191Y02807*
X03195Y02804*
Y02782*
X03222*
Y02831*
X03242*
Y02858*
X03241*
Y02875*
X03346Y0298*
X03351Y0298*
X03354Y02983*
X03409*
Y02975*
Y02973*
Y0297*
Y02968*
Y02927*
Y02926*
Y02922*
Y02921*
Y02901*
X03379*
X03377Y02903*
X0337Y02904*
X03364Y02903*
X03359Y02899*
X03355Y02894*
X03354Y02889*
X03292Y02827*
X03282*
Y02827*
X03255*
Y02798*
X03236*
Y02771*
X03261*
Y02782*
X03282*
Y02802*
X03297*
X03302Y02803*
X03306Y02806*
X03372Y02871*
X03377Y02872*
X03379Y02874*
X03409*
Y02861*
X03471*
Y02824*
X03455*
Y02769*
X03499*
Y02824*
X03498*
Y02861*
X03559*
Y02876*
X03564Y02876*
X03576Y02865*
Y02708*
X02827*
X02672Y02863*
Y03325*
X02898Y03551*
X04315*
X0462Y03246*
G37*
G36*
X06805Y02702D02*
X06352D01*
X06332Y02683*
Y02486*
X06116*
X0611Y02481*
X06106Y02482*
Y02771*
X0645*
X0646Y02781*
Y02968*
X06805*
Y02702*
G37*
G36*
X06942Y01511D02*
X06726Y01295D01*
X06663*
Y0159*
X06664*
Y01631*
X06663*
Y0165*
X06664*
Y01691*
X06663*
Y017*
X06664*
Y01741*
X06663*
Y01755*
X06664*
Y01788*
X06688Y01812*
X06692Y01812*
X06694Y01814*
X06705*
Y01788*
X06749*
Y01843*
X06753Y01846*
X06755*
X06759Y01843*
Y01788*
X06804*
Y01843*
X06808Y01846*
X0687*
X06874Y01843*
Y01788*
X06919*
Y01843*
X06923Y01846*
X06942*
Y01511*
G37*
%LNgrandmaster-2*%
%LPC*%
G36*
X069Y03647D02*
X06885Y03645D01*
X06871Y03639*
X06859Y0363*
X0685Y03618*
X06844Y03604*
X06842Y03589*
X06844Y03574*
X0685Y0356*
X06859Y03548*
X06871Y03539*
X06885Y03533*
X069Y03531*
X06915Y03533*
X06929Y03539*
X06941Y03548*
X0695Y0356*
X06955Y03574*
X06957Y03589*
X06955Y03604*
X0695Y03618*
X06941Y0363*
X06929Y03639*
X06915Y03645*
X069Y03647*
G37*
G36*
X06734D02*
X06719Y03645D01*
X06705Y03639*
X06694Y0363*
X06684Y03618*
X06679Y03604*
X06677Y03589*
X06679Y03574*
X06684Y0356*
X06694Y03548*
X06705Y03539*
X06719Y03533*
X06734Y03531*
X06749Y03533*
X06763Y03539*
X06775Y03548*
X06784Y0356*
X0679Y03574*
X06792Y03589*
X0679Y03604*
X06784Y03618*
X06775Y0363*
X06763Y03639*
X06749Y03645*
X06734Y03647*
G37*
G36*
X06569D02*
X06554Y03645D01*
X0654Y03639*
X06528Y0363*
X06519Y03618*
X06513Y03604*
X06511Y03589*
X06513Y03574*
X06519Y0356*
X06528Y03548*
X0654Y03539*
X06554Y03533*
X06569Y03531*
X06584Y03533*
X06598Y03539*
X0661Y03548*
X06619Y0356*
X06625Y03574*
X06627Y03589*
X06625Y03604*
X06619Y03618*
X0661Y0363*
X06598Y03639*
X06584Y03645*
X06569Y03647*
G37*
G36*
X03622Y03502D02*
X03616Y03501D01*
X03612Y03498*
X03566*
X03562Y03497*
X03558Y03494*
X03549Y03486*
X03544Y03488*
X03541Y03492*
X03536Y03496*
X03529Y03497*
X03523Y03496*
X03518Y03492*
X03514Y03487*
X03513Y03481*
X03514Y03474*
X03518Y03469*
X03522Y03466*
X03524Y03461*
X0351Y03446*
X03507Y03442*
X03506Y03438*
X03483*
X03482Y03439*
X03481Y03444*
X03484Y03449*
X03486Y03456*
X03484Y03462*
X03481Y03467*
X03476Y03471*
X03469Y03472*
X03463Y03471*
X03458Y03467*
X03456Y03464*
X03456Y03464*
X0345Y03465*
X03448Y03468*
X03443Y03472*
X03436Y03473*
X0343Y03472*
X03425Y03468*
X03424Y03468*
X03419Y03467*
X03411Y03475*
X03407Y03478*
X03403Y03479*
X03377*
X03373Y03478*
X03369Y03475*
X03357Y03464*
X03352Y03463*
X03348Y0346*
X03311*
X03306Y03465*
X03302Y03468*
X03297Y03468*
X03247*
X03242Y03468*
X03238Y03465*
X03126Y03353*
X03123Y03349*
X03122Y03344*
Y03307*
X03083*
X03075Y03305*
X03069Y03301*
X03065Y03294*
X03063Y03287*
X03065Y03279*
X03069Y03272*
X03075Y03268*
X03083Y03267*
X03138*
X03146Y03268*
X03153Y03272*
X03157Y03279*
X03158Y03287*
X03157Y03294*
X03153Y03301*
X03147Y03305*
Y03339*
X03252Y03444*
X03292*
X03297Y03439*
X03301Y03436*
X03305Y03435*
Y03362*
X03302Y0336*
X03296Y03359*
X03291Y03355*
X03287Y0335*
X03286Y03344*
X03287Y03337*
X03291Y03332*
X03296Y03328*
X03302Y03327*
X03309Y03328*
X03312Y03331*
X03317Y03329*
Y0331*
X03315Y03307*
X03314Y03301*
X03315Y03294*
X03319Y03289*
X03321Y03287*
X03321Y03287*
X0332Y03282*
X03265*
X03265Y03287*
X03266Y03288*
X03269Y03288*
X03275Y03292*
X03278Y03297*
X0328Y03303*
X03278Y0331*
X03275Y03315*
X03269Y03318*
X03263Y0332*
X03257Y03318*
X03252Y03315*
X03248Y0331*
X03247Y03303*
X03248Y03297*
X03252Y03292*
X03257Y03288*
X0326Y03288*
X03262Y03287*
X03261Y03282*
X03205*
X03201Y03281*
X03197Y03279*
X03167Y03249*
X03154*
X03153Y03251*
X03146Y03255*
X03138Y03257*
X03083*
X03075Y03255*
X03069Y03251*
X03065Y03244*
X03063Y03237*
X03065Y03229*
X03069Y03222*
X03075Y03218*
X03083Y03217*
X03138*
X03146Y03218*
X03153Y03222*
X03154Y03224*
X03172*
X03176Y03225*
X0318Y03228*
X0321Y03258*
X03328*
X03333Y03259*
X03337Y03262*
X03354Y03279*
X03359Y03276*
X03358Y03273*
X03359Y03266*
X03363Y03261*
X03368Y03257*
X03374Y03256*
X03381Y03257*
X03386Y03261*
X03389Y03266*
X03391Y03273*
X03389Y03279*
X03386Y03284*
X03381Y03288*
X03374Y03289*
X03371Y03288*
X03368Y03293*
X03393Y03318*
X03423Y03288*
X03427Y03285*
X03431Y03284*
X03481*
X03485Y03281*
X03491Y0328*
X03498Y03281*
X03503Y03285*
X03506Y0329*
X03508Y03297*
X03506Y03303*
X03503Y03308*
X03498Y03312*
X03491Y03313*
X03485Y03312*
X03481Y03309*
X03436*
X03405Y0334*
Y03351*
X03419*
X03423*
X03477*
X03478*
X03482*
X03483*
X03536*
X03537*
X03541Y03348*
Y03335*
X03536Y03334*
X03531Y0333*
X03527Y03325*
X03526Y03319*
X03527Y03312*
X03531Y03307*
X03536Y03303*
X03542Y03302*
X03549Y03303*
X03554Y03307*
X03557Y03312*
X03559Y03319*
X03557Y03325*
X03556Y03327*
X03559Y03332*
X03597*
Y03438*
X03543*
X03541Y03443*
X03571Y03473*
X03612*
X03616Y0347*
X03622Y03469*
X03629Y0347*
X03634Y03474*
X03637Y03479*
X03639Y03486*
X03637Y03492*
X03634Y03497*
X03629Y03501*
X03622Y03502*
G37*
G36*
X03068Y03411D02*
X03062Y0341D01*
X03057Y03407*
X03048*
X03044Y03406*
X0304Y03404*
X02835Y03199*
X028*
X02798Y03201*
X02792Y03205*
X02784Y03207*
X02729*
X02721Y03205*
X02715Y03201*
X0271Y03194*
X02709Y03187*
X0271Y03179*
X02715Y03172*
X02721Y03168*
X02729Y03167*
X02784*
X02792Y03168*
X02798Y03172*
X028Y03174*
X0284*
X02845Y03175*
X02849Y03178*
X03053Y03383*
X03058*
X03062Y0338*
X03068Y03379*
X03075Y0338*
X0308Y03384*
X03083Y03389*
X03085Y03395*
X03083Y03401*
X0308Y03407*
X03075Y0341*
X03068Y03411*
G37*
G36*
X03744Y03358D02*
X03738Y03357D01*
X03735Y03355*
X03715*
Y03357*
X03662*
Y03312*
X03657Y03308*
X03653Y03309*
X03647Y03308*
X03642Y03304*
X03638Y03299*
X03637Y03293*
X03638Y03286*
X03642Y03281*
X03647Y03277*
X03653Y03276*
X0366Y03277*
X03665Y03281*
X03668Y03286*
X0367Y03293*
X03669Y03296*
X03672Y03301*
X03715*
Y03328*
X03735*
X03738Y03326*
X03744Y03325*
X03751Y03326*
X03756Y0333*
X03759Y03335*
X03761Y03342*
X03759Y03348*
X03756Y03353*
X03751Y03357*
X03744Y03358*
G37*
G36*
X02784Y03307D02*
X02729D01*
X02721Y03305*
X02715Y03301*
X0271Y03294*
X02709Y03287*
X0271Y03279*
X02715Y03272*
X02721Y03268*
X02729Y03267*
X02784*
X02792Y03268*
X02798Y03272*
X02803Y03279*
X02804Y03287*
X02803Y03294*
X02798Y03301*
X02792Y03305*
X02784Y03307*
G37*
G36*
X03482Y03249D02*
X03478D01*
X03477*
X03424*
X03423*
X03419*
X03418*
X03365*
X03364*
X0336*
X03359*
X03305*
Y0318*
X03282Y03156*
X03281Y03156*
X03275Y03158*
X03269Y03156*
X03264Y03153*
X0326Y03147*
X03259Y03141*
X0326Y03135*
X03264Y0313*
X03269Y03126*
X03275Y03125*
X03281Y03126*
X03287Y0313*
X03287Y03131*
X0329Y03131*
X03294Y03134*
X03322Y03162*
X03359*
X0336*
X03364*
X03365*
X03418*
X03419*
X03423*
X03424*
X03477*
X03478*
X03482*
X03483*
X03537*
Y03249*
X03483*
X03482*
G37*
G36*
X03744Y03277D02*
X03738Y03276D01*
X03733Y03272*
X03729Y03267*
X03728Y03261*
X03729Y03254*
X03733Y03249*
X03738Y03245*
X03744Y03244*
X03751Y03245*
X03756Y03249*
X03759Y03254*
X03761Y03261*
X03759Y03267*
X03756Y03272*
X03751Y03276*
X03744Y03277*
G37*
G36*
X0323Y03251D02*
X03224Y0325D01*
X03219Y03246*
X03215Y03241*
X03214Y03235*
X03215Y03228*
X03219Y03223*
X03224Y03219*
X0323Y03218*
X03237Y03219*
X03242Y03223*
X03245Y03228*
X03247Y03235*
X03245Y03241*
X03242Y03246*
X03237Y0325*
X0323Y03251*
G37*
G36*
X03138Y03207D02*
X03083D01*
X03075Y03205*
X03069Y03201*
X03065Y03194*
X03063Y03187*
X03065Y03179*
X03069Y03172*
X03075Y03168*
X03083Y03167*
X03138*
X03146Y03168*
X03153Y03172*
X03154Y03174*
X03178*
X03182Y03171*
X03188Y0317*
X03195Y03171*
X032Y03175*
X03204Y0318*
X03205Y03187*
X03204Y03193*
X032Y03198*
X03195Y03202*
X03188Y03203*
X03182Y03202*
X03178Y03199*
X03154*
X03153Y03201*
X03146Y03205*
X03138Y03207*
G37*
G36*
X04477Y03151D02*
X04471Y0315D01*
X04466Y03146*
X04462Y03141*
X04461Y03135*
X04461Y03133*
X04453Y03124*
X04447Y03126*
X04446Y03128*
X04446Y03128*
X04448Y03135*
X04446Y03141*
X04443Y03146*
X04438Y0315*
X04431Y03151*
X04425Y0315*
X0442Y03146*
X04416Y03141*
X04415Y03135*
X04416Y03128*
X04418Y03126*
Y0312*
X04397Y03099*
X04374*
Y03056*
X04415*
Y03079*
X04429Y03094*
X04434Y03092*
Y03056*
X04475*
Y03099*
X04471*
X04469Y03104*
X04486Y0312*
X04487Y03121*
X04489Y03123*
X04492Y03128*
X04494Y03135*
X04492Y03141*
X04489Y03146*
X04484Y0315*
X04477Y03151*
G37*
G36*
X03138Y03157D02*
X03083D01*
X03075Y03155*
X03069Y03151*
X03065Y03144*
X03063Y03137*
X03065Y03129*
X03069Y03122*
X03075Y03118*
X03083Y03117*
X03138*
X03146Y03118*
X03153Y03122*
X03153Y03123*
X03172*
X03176Y0312*
X03183Y03119*
X03189Y0312*
X03194Y03124*
X03198Y03129*
X03199Y03135*
X03198Y03142*
X03194Y03147*
X03189Y0315*
X03183Y03152*
X03176Y0315*
X03172Y03148*
X03155*
X03153Y03151*
X03146Y03155*
X03138Y03157*
G37*
G36*
X02784D02*
X02729D01*
X02721Y03155*
X02715Y03151*
X0271Y03144*
X02709Y03137*
X0271Y03129*
X02715Y03122*
X02721Y03118*
X02729Y03117*
X02784*
X02792Y03118*
X02798Y03122*
X02803Y03129*
X02804Y03137*
X02803Y03144*
X02798Y03151*
X02792Y03155*
X02784Y03157*
G37*
G36*
X03939Y03137D02*
X03933Y03136D01*
X03928Y03132*
X03924Y03127*
X03923Y03121*
X03924Y03114*
X03928Y03109*
X03933Y03105*
X03939Y03104*
X03946Y03105*
X03951Y03109*
X03954Y03114*
X03956Y03121*
X03954Y03127*
X03951Y03132*
X03946Y03136*
X03939Y03137*
G37*
G36*
X03806Y03251D02*
X038Y0325D01*
X03795Y03246*
X03791Y03241*
X0379Y03235*
X03791Y03228*
X03793Y03226*
X03789Y03222*
X03787*
X03749*
Y03179*
X03772*
X03852Y03099*
X03856Y03096*
X03861Y03095*
X03871*
X03874Y03093*
X0388Y03092*
X03887Y03093*
X03892Y03097*
X03895Y03102*
X03897Y03109*
X03895Y03115*
X03892Y0312*
X03887Y03124*
X0388Y03125*
X03874Y03124*
X03871Y03122*
X03867*
X03858Y03131*
X0386Y03135*
X03861Y03135*
X03866Y03139*
X03869Y03144*
X03871Y03151*
X03869Y03157*
X03866Y03162*
X03861Y03166*
X03854Y03167*
X03848Y03166*
X03848Y03165*
X03844Y03169*
X03844Y03169*
X03846Y03176*
X03844Y03182*
X03841Y03187*
X03836Y03191*
X03829Y03192*
X03823Y03191*
X03818Y03187*
X03816Y03184*
X0381Y03183*
X0381Y03183*
X0381Y03188*
X03811Y03189*
X03814Y03194*
X03816Y03201*
X03814Y03207*
X03811Y03212*
X03809Y03214*
X0381Y03219*
X03813Y03219*
X03818Y03223*
X03821Y03228*
X03823Y03235*
X03821Y03241*
X03818Y03246*
X03813Y0325*
X03806Y03251*
G37*
G36*
X03138Y03107D02*
X03083D01*
X03075Y03105*
X03069Y03101*
X03065Y03094*
X03063Y03087*
X03065Y03079*
X03069Y03072*
X03075Y03068*
X03083Y03067*
X03138*
X03146Y03068*
X03153Y03072*
X03157Y03079*
X03158Y03087*
X03157Y03094*
X03153Y03101*
X03146Y03105*
X03138Y03107*
G37*
G36*
X02784D02*
X02729D01*
X02721Y03105*
X02715Y03101*
X0271Y03094*
X02709Y03087*
X0271Y03079*
X02715Y03072*
X02721Y03068*
X02729Y03067*
X02784*
X02792Y03068*
X02798Y03072*
X02803Y03079*
X02804Y03087*
X02803Y03094*
X02798Y03101*
X02792Y03105*
X02784Y03107*
G37*
G36*
X04068Y03151D02*
X04062Y0315D01*
X04057Y03146*
X04053Y03141*
X04053Y03138*
X04043Y03128*
X0404Y03124*
X04039Y0312*
X04013*
Y03064*
X04066*
Y03114*
X04071Y03119*
X04075Y03119*
X0408Y03123*
X04083Y03128*
X04085Y03135*
X04083Y03141*
X0408Y03146*
X04075Y0315*
X04068Y03151*
G37*
G36*
X04333D02*
X04327Y0315D01*
X04322Y03146*
X04318Y03141*
X04317Y03135*
X04318Y03128*
X04321Y03124*
Y03099*
X04314*
Y03056*
X04355*
Y03099*
X04348*
Y03127*
X04348Y03128*
X0435Y03135*
X04348Y03141*
X04345Y03146*
X0434Y0315*
X04333Y03151*
G37*
G36*
X04272D02*
X04266Y0315D01*
X04261Y03146*
X04257Y03141*
X04256Y03135*
X04257Y03128*
X04259Y03126*
Y03099*
X04254*
Y03056*
X04295*
Y03099*
X04286*
Y03126*
X04287Y03128*
X04289Y03135*
X04287Y03141*
X04284Y03146*
X04279Y0315*
X04272Y03151*
G37*
G36*
X0424Y03282D02*
X04178D01*
Y03209*
X04196*
Y03144*
X04193Y03141*
X04192Y03135*
X04193Y03128*
X04197Y03123*
X04199Y03121*
X042Y0312*
X04206Y03114*
Y03099*
X04199*
Y03056*
X0424*
Y03099*
X04233*
Y0312*
X04232Y03125*
X04229Y03129*
X04224Y03133*
X04225Y03135*
X04223Y03141*
X04222Y03143*
Y03209*
X0424*
Y03282*
G37*
G36*
X04152Y03151D02*
X04146Y0315D01*
X04141Y03146*
X04137Y03141*
X04136Y03135*
X04137Y03128*
X04141Y03123*
X04141Y03123*
X04141Y03122*
X04144Y03118*
X04151Y03111*
Y03099*
X04144*
Y03056*
X04185*
Y03099*
X04178*
Y03117*
X04177Y03122*
X04174Y03126*
X04168Y03132*
X04169Y03135*
X04167Y03141*
X04164Y03146*
X04159Y0315*
X04152Y03151*
G37*
G36*
X04114D02*
X04108Y0315D01*
X04103Y03146*
X04099Y03141*
X04098Y03135*
X04098Y03133*
X04097Y03131*
X04096Y03126*
Y03099*
X04089*
Y03056*
X0413*
Y03099*
X04123*
Y0312*
X04124Y03121*
X04126Y03123*
X04129Y03128*
X04131Y03135*
X04129Y03141*
X04126Y03146*
X04121Y0315*
X04114Y03151*
G37*
G36*
X0373Y03148D02*
X03657D01*
Y03086*
X03704*
Y03081*
X03702Y03078*
X03701Y03072*
X03702Y03065*
X03706Y0306*
X03711Y03056*
X03717Y03055*
X03724Y03056*
X03729Y0306*
X03732Y03065*
X03734Y03072*
X03732Y03078*
X03731Y03081*
Y03093*
X0373Y03095*
Y03099*
X0373Y03101*
Y03148*
G37*
G36*
X03138Y03057D02*
X03083D01*
X03075Y03055*
X03069Y03051*
X03065Y03044*
X03063Y03037*
X03065Y03029*
X03069Y03022*
X03075Y03018*
X03083Y03017*
X03138*
X03146Y03018*
X03153Y03022*
X03157Y03029*
X03158Y03037*
X03157Y03044*
X03153Y03051*
X03146Y03055*
X03138Y03057*
G37*
G36*
X02784D02*
X02729D01*
X02721Y03055*
X02715Y03051*
X0271Y03044*
X02709Y03037*
X0271Y03029*
X02715Y03022*
X02721Y03018*
X02729Y03017*
X02784*
X02792Y03018*
X02798Y03022*
X02803Y03029*
X02804Y03037*
X02803Y03044*
X02798Y03051*
X02792Y03055*
X02784Y03057*
G37*
G36*
X03138Y03007D02*
X03083D01*
X03075Y03005*
X03069Y03001*
X03065Y02994*
X03063Y02987*
X03065Y02979*
X03069Y02972*
X03075Y02968*
X03083Y02967*
X03138*
X03146Y02968*
X03153Y02972*
X03157Y02979*
X03158Y02987*
X03157Y02994*
X03153Y03001*
X03146Y03005*
X03138Y03007*
G37*
G36*
X02784D02*
X02729D01*
X02721Y03005*
X02715Y03001*
X0271Y02994*
X02709Y02987*
X0271Y02979*
X02715Y02972*
X02721Y02968*
X02729Y02967*
X02784*
X02792Y02968*
X02798Y02972*
X02803Y02979*
X02804Y02987*
X02803Y02994*
X02798Y03001*
X02792Y03005*
X02784Y03007*
G37*
G36*
X03138Y02957D02*
X03083D01*
X03075Y02955*
X03069Y02951*
X03065Y02944*
X03063Y02937*
X03065Y02929*
X03069Y02922*
X03075Y02918*
X03083Y02917*
X03138*
X03146Y02918*
X03153Y02922*
X03157Y02929*
X03158Y02937*
X03157Y02944*
X03153Y02951*
X03146Y02955*
X03138Y02957*
G37*
G36*
X02784D02*
X02729D01*
X02721Y02955*
X02715Y02951*
X0271Y02944*
X02709Y02937*
X0271Y02929*
X02715Y02922*
X02721Y02918*
X02729Y02917*
X02784*
X02792Y02918*
X02798Y02922*
X02803Y02929*
X02804Y02937*
X02803Y02944*
X02798Y02951*
X02792Y02955*
X02784Y02957*
G37*
%LNgrandmaster-3*%
%LPD*%
G54D13*
X03987Y03783D02*
X04039D01*
X04039Y03784*
X02606Y00931D02*
X02608Y00934D01*
X02606Y00878D02*
Y00931D01*
X02409Y01038D02*
Y01088D01*
X02724Y01093D02*
X02724Y0109D01*
Y01038D02*
Y0109D01*
X02783Y01038D02*
Y01091D01*
X02784Y01094*
X02842Y01095D02*
X02842Y01095D01*
Y01038D02*
Y01095D01*
X02311Y00933D02*
X02311Y00934D01*
X02783Y02358D02*
Y02429D01*
X03463Y01713D02*
X03491D01*
X02475Y02456D02*
X02488Y02468D01*
X03556Y02047D02*
X03571Y02033D01*
X02586Y02317D02*
Y02358D01*
X02881Y02566D02*
X02882Y02565D01*
X03571Y02033D02*
X03594D01*
X01721Y01988D02*
X01776D01*
X02291Y02518D02*
X02291Y02518D01*
X02291Y02316D02*
Y02358D01*
X01718Y01497D02*
X01719Y01496D01*
X03571Y02033D02*
X03586Y02047D01*
X03596Y01514D02*
X03598Y01516D01*
X02488Y02412D02*
X02488Y02413D01*
X02291Y02556D02*
X02321Y02586D01*
X03409Y01465D02*
Y01468D01*
X01722Y01693D02*
X01776D01*
X02685Y02311D02*
Y02358D01*
X03457Y01516D02*
X03492D01*
X02901Y01095D02*
X02901Y01094D01*
X0239Y0256D02*
X02408Y02579D01*
X03594Y02033D02*
X03599Y02028D01*
X02586Y02518D02*
Y02568D01*
X02882Y02518D02*
Y02565D01*
X01645Y01497D02*
X01671D01*
X02488Y02468D02*
Y02518D01*
X03492Y02087D02*
X03542D01*
X02783Y02518D02*
Y02568D01*
X03414Y01805D02*
X03421Y01811D01*
X02488Y02358D02*
Y02412D01*
X02311Y0109D02*
X02312Y01091D01*
X02606Y0109D02*
X02606Y01091D01*
X03409Y01468D02*
X03448Y01506D01*
X02508Y01089D02*
X02508Y0109D01*
X01671Y01398D02*
X01671Y01399D01*
X02901Y00921D02*
X02933Y00953D01*
X03601Y02087D02*
X03651D01*
Y01418D02*
X03732D01*
X01717Y01398D02*
X01776D01*
X03718Y01713D02*
X03718Y01713D01*
X01722Y0189D02*
X01776D01*
X0167Y01693D02*
X0167Y01694D01*
X02311Y00878D02*
Y00933D01*
X03571Y02058D02*
X03581Y02067D01*
X0359Y01634D02*
Y01662D01*
X03491Y01713D02*
X03492Y01713D01*
X02408Y02579D02*
X02409D01*
X02685Y02518D02*
Y02567D01*
X03599Y02028D02*
X03651D01*
X03609Y01614D02*
X03651D01*
X01617Y01988D02*
X01674D01*
X02409Y00878D02*
Y00932D01*
X02882Y02307D02*
Y02358D01*
X03463Y01713D02*
X03463Y01713D01*
X0239Y02358D02*
Y02397D01*
X02253Y02279D02*
X02291Y02316D01*
X03581Y02067D02*
X03601Y02087D01*
X03594Y01514D02*
X03596D01*
X01675Y0189D02*
X01675Y01891D01*
X02665Y01038D02*
Y01091D01*
X03406Y01462D02*
X03409Y01465D01*
X01715Y01595D02*
X01776D01*
X01721Y01989D02*
X01721Y01988D01*
X03413Y01573D02*
Y01593D01*
X01721Y0189D02*
X01722Y0189D01*
X02508Y01038D02*
Y01089D01*
X0239Y02397D02*
X02404Y02412D01*
X01617Y01398D02*
X01671D01*
X02901Y00878D02*
Y00921D01*
X03581Y02067D02*
X03651D01*
X01617Y0189D02*
X01675D01*
X02665Y01091D02*
X02665Y01092D01*
X03651Y01713D02*
X03718D01*
X03406Y01461D02*
Y01462D01*
X02508Y00878D02*
Y00931D01*
X02311Y01038D02*
Y0109D01*
X02606Y01038D02*
Y0109D01*
X03448Y01506D02*
Y01507D01*
X01718Y01792D02*
X01718Y01792D01*
X03548Y01413D02*
X03549D01*
X01645Y01496D02*
X01645Y01497D01*
X01617Y01792D02*
X01671D01*
X03492Y02067D02*
X03562D01*
X01617Y01693D02*
X0167D01*
X02581Y02312D02*
X02586Y02317D01*
X03562Y02067D02*
X03571Y02058D01*
X0359Y01634D02*
X03609Y01614D01*
X01674Y01988D02*
X01674Y01989D01*
X02871Y02297D02*
X02882Y02307D01*
X02685Y02567D02*
X02685Y02568D01*
X0341Y01713D02*
X03463D01*
X03421Y01811D02*
X03492D01*
X02901Y01038D02*
Y01094D01*
X02291Y02518D02*
Y02556D01*
X0239Y02518D02*
Y0256D01*
X03492Y02028D02*
X0355D01*
X01719Y01496D02*
X01776D01*
X03586Y02047D02*
X03651D01*
X03598Y01516D02*
X03651D01*
X01617Y01595D02*
X0167D01*
X03492Y02047D02*
X03556D01*
X01714Y01595D02*
X01715Y01595D01*
X02586Y02569D02*
X02586Y02568D01*
X03413Y01593D02*
X03435Y01614D01*
X01721Y01694D02*
X01722Y01693D01*
X02685Y02311D02*
X02685Y02311D01*
X03448Y01507D02*
X03457Y01516D01*
X03435Y01614D02*
X03492D01*
X0167Y01595D02*
X0167Y01595D01*
X0355Y02028D02*
X03554Y02033D01*
X01718Y01792D02*
X01776D01*
X03543Y01418D02*
X03548Y01413D01*
X01617Y01496D02*
X01645D01*
X01617Y01792D02*
X01617Y01792D01*
X03542Y02087D02*
X03562Y02067D01*
X01617Y01496D02*
X01617Y01496D01*
X03554Y02033D02*
X03571D01*
X01716Y01399D02*
X01717Y01398D01*
X03492Y01418D02*
X03543D01*
X0333Y03301D02*
Y03392D01*
X03333Y03395*
X01726Y04329D02*
X01727Y04328D01*
Y04273D02*
Y04328D01*
X01788Y04289D02*
Y04329D01*
X01933Y04257D02*
D01*
X01873Y04281D02*
X0189Y04299D01*
X01873Y0427D02*
Y04281D01*
X01933Y04129D02*
Y04257D01*
X04476Y03129D02*
Y03133D01*
X04477Y03135*
X04454Y03108D02*
X04476Y03129D01*
X04064Y02722D02*
Y0278D01*
X06628Y01372D02*
X06629Y01372D01*
Y01421*
X07011Y01939D02*
X07015Y01943D01*
X06974Y01939D02*
X07011D01*
X03911Y01639D02*
X03911Y01639D01*
X03957Y01659D02*
X03968Y01671D01*
X04033Y01547D02*
X04034Y01546D01*
X03925Y01599D02*
X03951D01*
X03925Y01599D02*
X03925Y01599D01*
X03911Y01599D02*
X03925D01*
X03969Y01552D02*
Y01581D01*
X03911Y01619D02*
X03911Y01619D01*
X03964D02*
X03994Y01589D01*
X0413Y01686D02*
X04131D01*
X04068Y01679D02*
X04123D01*
X04033Y01547D02*
Y01575D01*
X03996Y01711D02*
X04025Y01739D01*
X03994Y01551D02*
Y01589D01*
X04025Y01739D02*
X04068D01*
X03911Y01619D02*
X03964D01*
X03911Y01639D02*
X03969D01*
X04033Y01575*
X04123Y01679D02*
X0413Y01686D01*
X03911Y01659D02*
X03957D01*
X03951Y01599D02*
X03969Y01581D01*
X03959Y02725D02*
X0396Y02724D01*
X03959Y02725D02*
Y0278D01*
X03625Y00726D02*
X03659D01*
X03603Y00704D02*
X03625Y00726D01*
X03603Y00682D02*
Y00704D01*
X06439Y03026D02*
Y03071D01*
Y03026D02*
X06456Y03009D01*
X06619Y03039D02*
X06626Y03032D01*
X06584Y03039D02*
X06619D01*
X01908Y04129D02*
X01933D01*
X01878Y04099D02*
X01908Y04129D01*
X01846Y04099D02*
X01878D01*
X01914Y04276D02*
X01933Y04257D01*
X01879Y04276D02*
X01914D01*
X01873Y04244D02*
Y0427D01*
X01853Y04225D02*
X01873Y04244D01*
X01687Y04225D02*
X01853D01*
X01664Y04248D02*
X01687Y04225D01*
X01664Y04248D02*
Y04273D01*
X03477Y02797D02*
X03484Y02804D01*
Y02892*
X01788Y04289D02*
X01802Y04276D01*
X03772Y03758D02*
X03825D01*
X03829Y03762*
X0383*
X03344Y04221D02*
X03394D01*
X03395Y04222*
X04272Y03079D02*
X04274Y03077D01*
X04272Y03079D02*
Y03135D01*
X02139Y03697D02*
Y03738D01*
X04209Y03135D02*
Y03246D01*
X04208Y03135D02*
X04209Y03135D01*
X04209Y03129D02*
X04219Y0312D01*
X04209Y03129D02*
Y03133D01*
X04208Y03135D02*
X04209Y03133D01*
X04219Y03077D02*
Y0312D01*
X04164Y03077D02*
Y03117D01*
X04153Y03127D02*
X04164Y03117D01*
X04153Y03127D02*
Y03133D01*
X04152Y03135D02*
X04153Y03133D01*
X01157Y01956D02*
Y01956D01*
X012Y02*
X01248*
X04039Y03092D02*
X04052Y03105D01*
Y03119*
X04068Y03135*
X01631Y04099D02*
X01671D01*
X01691Y04079*
X03642Y00636D02*
X03682D01*
X06477Y03231D02*
X06511D01*
X06476Y03231D02*
X06477Y03231D01*
X04334Y03077D02*
Y03134D01*
X04333Y03135D02*
X04334Y03134D01*
X04454Y03077D02*
Y03108D01*
X01873Y0427D02*
Y04276D01*
X01601Y04273D02*
X01664D01*
X01557Y04229D02*
X01601Y04273D01*
X01157Y02481D02*
X0126D01*
X01261Y02482*
X04109Y03077D02*
Y03126D01*
X04113Y03129*
Y03133*
X04114Y03135*
X06604Y03327D02*
X06618Y03341D01*
X06648*
X02888Y04221D02*
X02944D01*
X02888Y04221D02*
X02888Y04221D01*
X03434Y02888D02*
X03438Y02892D01*
X0337Y02888D02*
X03434D01*
X02233Y03734D02*
Y03735D01*
X02239Y03741*
X02209Y03716D02*
X02215D01*
X02233Y03734*
X02239Y03741D02*
X02258D01*
X01764Y04124D02*
X01846D01*
X01749Y0411D02*
X01764Y04124D01*
X02281Y0417D02*
Y04207D01*
X0229Y04217*
X03769Y032D02*
Y03201D01*
Y032D02*
X03777Y03192D01*
X03778*
X03861Y03109*
X0388*
X03688Y03329D02*
X03701Y03342D01*
X03744*
X03693Y03117D02*
X03699D01*
X03717Y03099*
Y03094D02*
Y03099D01*
Y03094D02*
X03717Y03093D01*
Y03072D02*
Y03093D01*
X05733Y03361D02*
Y03556D01*
X05676Y03362D02*
Y03545D01*
X05676Y03546*
X03659Y00723D02*
Y00726D01*
X06548Y01531D02*
X06629D01*
X06603Y01611D02*
X06642D01*
X06602Y01612D02*
X06603Y01611D01*
Y01671D02*
X06642D01*
X06602Y01672D02*
X06603Y01671D01*
Y01721D02*
X06642D01*
X06602Y01722D02*
X06603Y01721D01*
X06602Y01776D02*
X06642D01*
X06601Y01777D02*
X06602Y01776D01*
X06727Y01816D02*
Y01818D01*
X06718Y01828D02*
X06727Y01818D01*
X06685Y01828D02*
X06718D01*
X06637Y01881D02*
X06699D01*
X07009Y01938D02*
X0701Y01939D01*
X06906Y02096D02*
X06948D01*
X06949Y02095*
X0665Y02176D02*
X06659Y02166D01*
X06607Y02176D02*
X0665D01*
X06334Y0211D02*
X06395D01*
X06395Y02111*
X06048Y02171D02*
X06093D01*
X06004Y02393D02*
Y02434D01*
X06274Y02391D02*
X06352D01*
X06367Y02451D02*
X06369Y02453D01*
X06398*
X06361Y02501D02*
X06397D01*
X06361Y02556D02*
X06396D01*
X06361Y02611D02*
X06396D01*
X06397Y0261*
X06361Y02656D02*
X06397D01*
X06398Y02657*
X04954Y04203D02*
X04957Y04206D01*
X0491Y04203D02*
X04954D01*
X04387Y04206D02*
X04432D01*
X03778Y04023D02*
X03779Y04023D01*
X03777Y04023D02*
X03778D01*
X03779Y04023D02*
X03808D01*
X04104Y03841D02*
X04104Y03841D01*
X04104Y03841D02*
Y03873D01*
X04085Y03892D02*
X04104Y03873D01*
X04194Y03837D02*
Y03884D01*
X04394Y03077D02*
Y03078D01*
X04402Y03086*
X04403*
X04431Y03114*
Y03135*
X0286Y0375D02*
Y03784D01*
X0286Y03785*
X02745Y03742D02*
Y0375D01*
X0274Y03737D02*
X02745Y03742D01*
X02732Y03737D02*
X0274D01*
X02724Y03729D02*
X02732Y03737D01*
X02724Y03729D02*
Y03729D01*
X03495Y03697D02*
X03531Y03661D01*
Y0366D02*
Y03661D01*
X03495Y03697D02*
Y0375D01*
X0327D02*
Y03784D01*
X03269Y03785D02*
X0327Y03784D01*
X01157Y01431D02*
X01198Y01472D01*
X01242*
X01157Y00906D02*
X01193Y00942D01*
X01256*
X00654Y0079D02*
Y00847D01*
Y00964D02*
Y01027D01*
X00655Y01028*
X00654Y01314D02*
Y01372D01*
Y01489D02*
Y0155D01*
X00653Y01551D02*
X00654Y0155D01*
Y01839D02*
Y01897D01*
Y02014D02*
Y02073D01*
Y02365D02*
Y02422D01*
Y02539D02*
Y02593D01*
X00653Y02593D02*
X00654Y02593D01*
G54D17*
X01776Y02028D02*
X01776Y02028D01*
X01776Y02008D02*
X01776Y02008D01*
X03491Y01397D02*
X03492Y01398D01*
X03407Y01411D02*
X03431D01*
X03444Y01398*
X03492*
G54D19*
X02684Y02716D02*
D01*
X02685Y02716*
X02685Y02716*
X02686Y02716*
X02686Y02716*
X02687Y02717*
X02687Y02717*
X02688Y02717*
X02688Y02717*
X02689Y02718*
X02689Y02718*
X0269Y02718*
X0269Y02718*
X02449D02*
D01*
X02449Y02718*
X0245Y02718*
X0245Y02717*
X02451Y02717*
X02451Y02717*
X02452Y02717*
X02452Y02716*
X02453Y02716*
X02453Y02716*
X02454Y02716*
X02454Y02716*
X02455Y02716*
X02928Y00161D02*
D01*
X02929Y00159*
X02929Y00157*
X02929Y00154*
X0293Y00152*
X02931Y0015*
X02931Y00148*
X02932Y00145*
X02934Y00143*
X02935Y00141*
X02936Y00139*
X02938Y00138*
X02938Y00137*
X03985Y03759D02*
X03987Y03758D01*
X03948Y03759D02*
X03985D01*
X03934Y03774D02*
Y04023D01*
Y03774D02*
X03948Y03759D01*
X03902Y03743D02*
X03958Y03687D01*
X03902Y03743D02*
Y04023D01*
X03871Y03758D02*
Y04023D01*
X038Y03687D02*
X03871Y03758D01*
X04185Y03701D02*
X04194Y0371D01*
X04167Y03701D02*
X04185D01*
X04194Y0371D02*
Y03774D01*
X04104Y0377D02*
X04108Y03774D01*
X04194*
X04103Y03771D02*
X04104Y0377D01*
X04066Y03771D02*
X04103D01*
X03987Y03758D02*
X04053D01*
X04066Y03771*
X02378Y02789D02*
X02449Y02718D01*
X0269D02*
X02692Y02721D01*
X02455Y02716D02*
X02684D01*
X02494Y02614D02*
Y02661D01*
X03055Y00159D02*
Y00573D01*
Y00159D02*
X03057Y00157D01*
X02505Y00137D02*
X02507Y00139D01*
Y00271*
X02539Y00303D02*
Y00429D01*
X02507Y00271D02*
X02539Y00303D01*
X02503Y00464D02*
X02539Y00429D01*
X02503Y00464D02*
Y00573D01*
X0205Y00607D02*
X02503D01*
X01797Y00355D02*
X0205Y00607D01*
X02503D02*
X03055D01*
X03588Y02686D02*
Y0287D01*
X03534Y02888D02*
X03569D01*
X03588Y0287*
X03531Y02892D02*
X03534Y02888D01*
X03278Y01673D02*
X03492D01*
X03244Y01681D02*
X03271D01*
X03278Y01673*
X03252Y01661D02*
X03265D01*
X03272Y01654D02*
X03492D01*
X03265Y01661D02*
X03272Y01654D01*
X04133Y01751D02*
X04134Y01751D01*
X04121Y01751D02*
X04133D01*
X04068Y01759D02*
X04113D01*
X04121Y01751*
X04171Y01751D02*
X04727Y02307D01*
X04134Y01751D02*
X04171D01*
X04243Y01623D02*
X04927Y02307D01*
X0415Y01623D02*
X04243D01*
X05061Y01074D02*
Y02407D01*
Y01074D02*
X05127Y01007D01*
X05211Y01133D02*
Y0234D01*
X05327Y01007D02*
Y01017D01*
X05211Y01133D02*
X05327Y01017D01*
X04873Y02595D02*
X05061Y02407D01*
X04893Y02658D02*
X05211Y0234D01*
X0492Y02714D02*
X05327Y02307D01*
X04729Y02714D02*
X0492D01*
X02449Y02285D02*
Y02358D01*
Y02597D02*
X02463Y02612D01*
X02311Y02358D02*
X02331D01*
X01754Y02088D02*
X01755Y02087D01*
X03329Y01826D02*
X03405D01*
X02665Y02291D02*
Y02358D01*
X03492Y02008D02*
X03537D01*
X02894Y02465D02*
X02901Y02472D01*
X0292Y02517D02*
X02921Y02518D01*
X02841Y02299D02*
X02862Y02319D01*
X02499Y02236D02*
X02527Y02264D01*
X02429Y02303D02*
Y02322D01*
X02468Y02518D02*
Y02588D01*
X03491Y0185D02*
X03492Y01851D01*
X03378Y01971D02*
X03459Y0189D01*
X01567Y01285D02*
Y0131D01*
X03651Y01477D02*
X03652Y01478D01*
X03773Y01665D02*
Y01666D01*
X03409Y01363D02*
X03413Y01359D01*
X01776Y01516D02*
X01897D01*
X01719Y01536D02*
X01776D01*
X0298Y02518D02*
Y02599D01*
X03234Y01752D02*
X03492D01*
X0376Y01792D02*
X03804Y01836D01*
X02645Y02299D02*
X02646Y02299D01*
X02449Y02285D02*
X0245Y02284D01*
X02821Y02601D02*
X02823Y02599D01*
X03555Y0189D02*
X03651D01*
X02429Y02322D02*
X02429Y02322D01*
X02803Y02307D02*
Y02358D01*
X02645Y02274D02*
Y02299D01*
X02624Y02461D02*
X02626Y02459D01*
X0298Y02358D02*
Y02396D01*
X02862Y02319D02*
Y02358D01*
X02624Y02461D02*
X02625Y02461D01*
X02527Y02264D02*
Y02358D01*
X03412Y0185D02*
X03491D01*
X02646Y02299D02*
Y02358D01*
X01797Y01319D02*
X01798Y01318D01*
X02547Y02313D02*
Y02358D01*
X01617Y02087D02*
Y02118D01*
X03775Y01511D02*
X03864D01*
X03554Y01841D02*
X03584Y01811D01*
X03651Y01634D02*
X03696D01*
X03804Y01836D02*
Y0184D01*
X02429Y02322D02*
Y02358D01*
X02409Y02283D02*
X02429Y02303D01*
X02272Y02463D02*
Y02518D01*
X03699Y01654D02*
X03712Y01641D01*
X02449Y02518D02*
Y02597D01*
X01815Y01614D02*
X01893Y01693D01*
X03788Y01566D02*
X03894D01*
X03381Y01387D02*
X03422D01*
X02724Y02297D02*
X02726Y02295D01*
X01776Y01811D02*
X01879D01*
X01719Y01536D02*
X01719Y01536D01*
X02958Y02621D02*
X0298Y02599D01*
X03651Y02008D02*
X03707D01*
X03651Y0189D02*
X03651Y0189D01*
X02331Y02215D02*
Y02358D01*
X01776Y02067D02*
X01881D01*
X03405Y01826D02*
X03411Y01831D01*
X03459Y0189D02*
X03492D01*
X03422Y01387D02*
X03431Y01378D01*
X02961Y02311D02*
X02985Y02287D01*
X0235Y02676D02*
X02394Y0272D01*
X0235Y02518D02*
Y02676D01*
X03652Y01478D02*
X03831D01*
X03749Y01641D02*
X03773Y01665D01*
X0292Y02428D02*
X0292Y02428D01*
X01776Y01674D02*
X01822D01*
X01755Y02087D02*
X01776D01*
X02468Y02299D02*
Y02358D01*
X01617Y02118D02*
X01619Y02121D01*
X03528Y0191D02*
X03554Y01936D01*
X02702Y02293D02*
Y02295D01*
X03651Y0191D02*
X03708D01*
X03705Y01625D02*
X0377D01*
X03776Y01555D02*
X03795Y01536D01*
X03491Y0187D02*
X03492Y0187D01*
X02841Y02263D02*
Y02299D01*
X02702Y02295D02*
X02705Y02298D01*
X02409Y02314D02*
Y02358D01*
X01776Y01319D02*
X01797D01*
X03584Y01811D02*
X03651D01*
X03708Y0191D02*
X03719Y01921D01*
X03696Y01634D02*
X03705Y01625D01*
X03651Y01555D02*
X03776D01*
X03431Y01378D02*
X03492D01*
X02901Y02304D02*
X0292Y02286D01*
X02429Y02358D02*
X02429Y02358D01*
X02252Y02518D02*
Y02613D01*
X03712Y01641D02*
X03749D01*
X02547Y02313D02*
X02579Y02281D01*
X01776Y01614D02*
X01815D01*
X03651Y01575D02*
X03779D01*
X03197Y01714D02*
Y01715D01*
X03439Y0187D02*
X03491D01*
X03298Y01971D02*
X03378D01*
X0292Y02286D02*
X02942D01*
X02599Y02431D02*
Y02436D01*
X02468Y02588D02*
X02494Y02614D01*
X02894Y02431D02*
Y02465D01*
X02803Y02358D02*
X02803Y02358D01*
X02493Y02694D02*
X02494Y02696D01*
X01798Y01304D02*
Y01318D01*
X02948Y02428D02*
X0298Y02396D01*
X03492Y01438D02*
X03547D01*
X03715Y01772D02*
X03719Y01767D01*
X02901Y02304D02*
Y02358D01*
X02484Y02694D02*
X02493D01*
X01879Y01811D02*
X01882Y01809D01*
X01881Y02067D02*
X01884Y02071D01*
X03707Y02008D02*
X03719Y01996D01*
X02726Y02293D02*
Y02295D01*
X0233Y02215D02*
X02331Y02215D01*
X03392Y01871D02*
X03412Y0185D01*
X02823Y02518D02*
Y02599D01*
X01776Y01536D02*
X01776Y01536D01*
X01568Y02067D02*
X01617D01*
X03554Y01891D02*
X03555Y0189D01*
X03379Y01386D02*
X03381Y01387D01*
X02463Y02612D02*
Y02674D01*
X0292Y02428D02*
Y02517D01*
X01577Y01319D02*
X01617D01*
X03831Y01478D02*
X03834Y01481D01*
X03537Y02008D02*
X03554Y01991D01*
X03411Y01831D02*
X03492D01*
X02705Y0232D02*
Y02358D01*
X02901Y02472D02*
Y02518D01*
X02948Y02428D02*
Y02456D01*
X03761Y01496D02*
X03775Y01511D01*
X03492Y0191D02*
X03528D01*
X03804Y01659D02*
Y0169D01*
X02705Y0232D02*
X02705Y02319D01*
X02724Y02297D02*
Y02358D01*
X02475Y02291D02*
Y02292D01*
X0377Y01625D02*
X03804Y01659D01*
X03795Y01536D02*
X03924D01*
X03197Y01715D02*
X03234Y01752D01*
X03651Y01792D02*
X0376D01*
X03383Y01339D02*
X03492D01*
X02705Y02298D02*
Y02319D01*
X02468Y02299D02*
X02475Y02292D01*
X01754Y02088D02*
Y02126D01*
X03651Y01496D02*
X03761D01*
X03803Y01691D02*
X03804Y0169D01*
X03924Y01536D02*
D01*
X03404Y01363D02*
X03409D01*
X03379Y01336D02*
X03383Y01339D01*
X02961Y02311D02*
Y02358D01*
X02409Y02314D02*
X02409Y02314D01*
X02665Y02291D02*
X02665Y02291D01*
X02599Y02431D02*
X02606Y02424D01*
X02567Y02358D02*
Y02403D01*
X0245Y02282D02*
Y02284D01*
X03492Y01437D02*
X03492Y01438D01*
X03719Y01766D02*
Y01767D01*
X03413Y01359D02*
X03492D01*
X02606Y02358D02*
Y02424D01*
X02626Y02358D02*
Y02459D01*
X02567Y02403D02*
X02575Y02412D01*
X02463Y02674D02*
X02484Y02694D01*
X01567Y0131D02*
X01577Y01319D01*
X03779Y01575D02*
X03788Y01566D01*
X03651Y01654D02*
X03699D01*
X03651Y01772D02*
X03715D01*
X03547Y01438D02*
X03549Y01441D01*
X03224Y01661D02*
X03244Y01681D01*
X05577Y02214D02*
X05612D01*
X05634Y02236*
X04204Y03603D02*
X04275D01*
X03537Y02996D02*
X03547Y02985D01*
X03393Y03335D02*
X03431Y03297D01*
X03393Y03335D02*
Y03393D01*
Y03333D02*
Y03335D01*
X03392Y03395D02*
X03393Y03393D01*
X03328Y0327D02*
X0339Y03332D01*
X03431Y03297D02*
X03491D01*
X03205Y0327D02*
X03328D01*
X03425Y03666D02*
X03464D01*
X03349D02*
X03425D01*
X03424Y03636D02*
X03425Y03636D01*
Y03666*
X03464Y03648D02*
X03469Y03653D01*
X03608Y03727D02*
X03667Y03786D01*
X03589Y03727D02*
X03608D01*
X04141Y03594D02*
X0415Y03603D01*
X0412Y03594D02*
X04141D01*
X0096Y00714D02*
Y00718D01*
Y00714D02*
X00988Y00687D01*
X0099*
X00901Y00718D02*
Y00875D01*
X00932Y00906*
X04884Y02789D02*
X04887Y02786D01*
X04909Y02808D02*
D01*
X04794D02*
X04909D01*
X04794D02*
X04795Y02809D01*
X04909Y04118D02*
X0491Y04119D01*
X04909Y03961D02*
Y04118D01*
X04539Y02904D02*
X04729Y02714D01*
X04539Y02904D02*
Y03111D01*
X03112Y03135D02*
X03183D01*
X03111Y03137D02*
X03112Y03135D01*
X0491Y04119D02*
Y04203D01*
X03209Y02834D02*
Y02896D01*
X03271Y02958*
X03191Y02824D02*
Y02924D01*
X0325Y02983*
Y03042*
X03269Y02795D02*
Y02814D01*
X03297*
X0337Y02888*
X03487Y03101D02*
X03488Y03101D01*
X0331Y03101D02*
X03487D01*
X03491Y03101D02*
X03491Y03101D01*
X03484Y03094D02*
X03491Y03101D01*
X03488Y03101D02*
X03491D01*
X03111Y03187D02*
X03111Y03187D01*
X03188*
X03188Y03187*
X03111Y03237D02*
X03172D01*
X03205Y0327*
X03247Y03456D02*
X03297D01*
X03306Y03448D02*
X03358D01*
X03297Y03456D02*
X03306Y03448D01*
X03358D02*
X03377Y03467D01*
X03134Y03344D02*
X03247Y03456D01*
X03111Y03287D02*
X03127D01*
X03134Y03294*
Y03344*
X03068Y03395D02*
X03068Y03395D01*
X03048Y03395D02*
X03068D01*
X0284Y03187D02*
X03048Y03395D01*
X02756Y03187D02*
X0284D01*
X02146Y02679D02*
Y02753D01*
X03333Y0319D02*
Y03206D01*
X03285Y03143D02*
X03333Y0319D01*
X03277Y03143D02*
X03285D01*
X03275Y03141D02*
X03277Y03143D01*
X02378Y0289D02*
X02387Y02899D01*
X02378Y02789D02*
Y0289D01*
X02387Y02958D02*
X02389Y0296D01*
Y03481*
X02333D02*
X02389D01*
X02329Y03484D02*
X02333Y03481D01*
X02452Y03563D02*
X02504D01*
X02264Y03545D02*
X02311D01*
X02329Y03563*
X02504Y03484D02*
X02578D01*
X02434Y03546D02*
X02452Y03563D01*
X02254Y03536D02*
X02264Y03545D01*
X02504Y03406D02*
X02634D01*
X02578Y03484D02*
X02579Y03486D01*
X00995Y02257D02*
X00996Y02256D01*
X00967Y0228D02*
X0099Y02257D01*
X00995*
X02212Y04074D02*
X02242D01*
X02253Y04086*
X02146Y04076D02*
X02147Y04074D01*
X02146Y04076D02*
Y04103D01*
X02147Y04074D02*
X02151D01*
X01346Y03978D02*
X01348Y0398D01*
X01408*
X01345Y04142D02*
X01346Y04141D01*
X01345Y04142D02*
Y04175D01*
X00963Y0122D02*
Y01224D01*
Y0122D02*
X00996Y01187D01*
Y01187D02*
Y01187D01*
X00959Y01743D02*
Y01747D01*
Y01743D02*
X00983Y01719D01*
X00986*
X00988Y01717*
X00967Y0228D02*
Y02284D01*
X00904Y01224D02*
Y01402D01*
X00932Y01431*
X009Y01747D02*
Y01924D01*
X00932Y01956*
X00908Y02284D02*
Y02456D01*
X00932Y02481*
X02151Y04014D02*
X0221D01*
X02043Y04057D02*
X02086Y04014D01*
X02151*
X01715Y03963D02*
X02245D01*
X02332Y04051D02*
Y0417D01*
X02245Y03963D02*
X02332Y04051D01*
X02358Y04022D02*
Y0417D01*
X02353Y04017D02*
X02358Y04022D01*
X01346Y04037D02*
Y04082D01*
Y04037D02*
X01356Y04047D01*
X0145*
X01457Y04053*
Y04153D02*
X01487Y04124D01*
X01569Y04171D02*
Y04173D01*
X01594Y04197*
X01659Y04019D02*
X01715Y03963D01*
X0325Y03042D02*
X0331Y03101D01*
X03208Y02815D02*
X03209Y02814D01*
X032Y02815D02*
X03208D01*
X03191Y02824D02*
X032Y02815D01*
X03229Y02845D02*
Y0288D01*
X03344Y02996*
X04539Y03111D02*
Y03156D01*
X04243Y02658D02*
X04893D01*
X0418Y02595D02*
X04243Y02658D01*
X04298Y02595D02*
X04873D01*
X04187Y02469D02*
X04912D01*
X04062Y02595D02*
X04187Y02469D01*
X04992Y01071D02*
Y02389D01*
X04912Y02469D02*
X04992Y02389D01*
X04927Y02307D02*
D01*
X04126Y01631D02*
X04142D01*
X0415Y01623*
X04927Y01007D02*
X04992Y01071D01*
X04068Y01659D02*
X04126D01*
X04179Y01601D02*
D01*
X04065Y01599D02*
X04068D01*
X04064Y01511D02*
Y01598D01*
Y0178D02*
X04065Y01779D01*
X04068Y01619D02*
X04117D01*
X04064Y01598D02*
X04065Y01599D01*
X04117Y01619D02*
X04135Y01601D01*
X0392Y01791D02*
X03944Y01816D01*
X04135Y01601D02*
X04179D01*
X04118Y01639D02*
X04126Y01631D01*
X04126Y01659D02*
X04134Y01651D01*
X03911Y01779D02*
X03919D01*
X04134Y01651D02*
X04134D01*
X04068Y01639D02*
X04118D01*
X0392Y0178D02*
Y01791D01*
X03919Y01779D02*
X0392Y0178D01*
X04065Y01779D02*
X04068D01*
X04064Y0178D02*
Y01796D01*
X05812Y03302D02*
Y03361D01*
X01629Y04197D02*
X01631Y04199D01*
X01594Y04197D02*
X01629D01*
X01569Y04171D02*
D01*
X02527Y02518D02*
Y02582D01*
X02612Y02666D02*
X03568D01*
X02527Y02582D02*
X02612Y02666D01*
X03568D02*
X03588Y02686D01*
X01487Y04124D02*
X01631D01*
X03057Y0013D02*
X03059Y00132D01*
X01893Y04018D02*
X01903D01*
X01886Y04024D02*
X01893Y04018D01*
X01846Y04024D02*
X01886D01*
X02758Y03661D02*
X02797Y03701D01*
X02719Y03661D02*
X02758D01*
X02797Y03701D02*
X03D01*
X0373Y00731D02*
X03737Y00724D01*
X03979Y00808D02*
Y0089D01*
X03895Y00724D02*
X03979Y00808D01*
X03737Y00724D02*
X03895D01*
X03716Y00712D02*
X0373Y00726D01*
X03716Y00636D02*
Y00712D01*
X06679Y02339D02*
Y0242D01*
X06643Y02302D02*
X06679Y02339D01*
X06469Y02302D02*
X06643D01*
X06435D02*
X06469D01*
X06397Y02341D02*
X06435Y02302D01*
X06352Y02341D02*
X06397D01*
X06788Y01881D02*
X06832D01*
X06782Y01874D02*
X06788Y01881D01*
X06782Y01874D02*
Y01816D01*
X06897D02*
Y01864D01*
X0688Y01881D02*
X06897Y01864D01*
X06832Y01881D02*
X0688D01*
X06359Y0331D02*
X06388D01*
X06336Y03287D02*
X06359Y0331D01*
X06336Y03267D02*
Y03287D01*
X0649Y03172D02*
X06511D01*
X06489Y03173D02*
X0649Y03172D01*
X0642Y0313D02*
Y0315D01*
X0641Y03121D02*
X0642Y0313D01*
X06304Y03121D02*
X0641D01*
X01017Y03836D02*
X02029D01*
X0084Y04013D02*
X01017Y03836D01*
X00835Y03816D02*
X02004D01*
X00638Y04012D02*
X00835Y03816D01*
X00638Y04012D02*
Y04038D01*
X01363Y03896D02*
X02084D01*
X01243Y04015D02*
X01363Y03896D01*
X01243Y04015D02*
Y04038D01*
X01185Y03871D02*
X02059D01*
X01042Y04014D02*
X01185Y03871D01*
X01042Y04014D02*
Y04038D01*
X0084Y04013D02*
Y04038D01*
X01774Y04049D02*
X01846D01*
X01676Y04147D02*
X01774Y04049D01*
X01633Y04147D02*
X01676D01*
X02146Y02578D02*
Y02624D01*
X02108Y0254D02*
X02146Y02578D01*
X02108Y01728D02*
Y0254D01*
X02229Y02586D02*
X02232Y02583D01*
Y02518D02*
Y02583D01*
X06604Y03192D02*
X06704D01*
X06726Y0317*
Y03168D02*
Y0317D01*
X06604Y03191D02*
X06604Y03192D01*
X06511Y03191D02*
X06604D01*
X06604Y03264D02*
X06704D01*
X06726Y03286*
Y03294*
X06604Y03263D02*
Y03264D01*
X06552Y03211D02*
X06604Y03263D01*
X06511Y03211D02*
X06552D01*
X00644Y04099D02*
Y04197D01*
X00638Y04093D02*
X00644Y04099D01*
X00846D02*
Y04192D01*
X0084Y04093D02*
X00846Y04099D01*
X03053Y00571D02*
X03055Y00573D01*
X06234Y02183D02*
Y02241D01*
X06184Y02291D02*
X06234Y02241D01*
X06157Y02291D02*
X06184D01*
X06804Y01881D02*
X06832D01*
X06122Y02433D02*
X06128D01*
X06138Y02423*
Y02418D02*
Y02423D01*
Y02418D02*
X06147Y02409D01*
Y02398D02*
Y02409D01*
Y02398D02*
X06154Y02391D01*
X06157*
X06184*
X06244Y02451*
X06312*
X02944Y03745D02*
Y03951D01*
X03144Y03745D02*
Y03951D01*
X03349Y03745D02*
Y03946D01*
X03344Y03951D02*
X03349Y03946D01*
X04112Y03701D02*
Y03706D01*
X04085Y03733D02*
X04112Y03706D01*
X03987Y03733D02*
X04085D01*
X04566Y04206D02*
X04652D01*
Y04121D02*
Y04206D01*
D01*
X05091D02*
X05212D01*
Y04126D02*
Y04206D01*
Y04126D02*
D01*
X01846Y04074D02*
X01933D01*
X01933Y04074*
X04049Y03665D02*
Y03694D01*
X04035Y03708D02*
X04049Y03694D01*
X03987Y03708D02*
X04035D01*
X03827Y03808D02*
X03829Y03806D01*
X03772Y03808D02*
X03827D01*
X01631Y04149D02*
X01633Y04147D01*
X06379Y03309D02*
X06388D01*
X06388Y0331D02*
X06388Y03309D01*
X06334Y03266D02*
Y03269D01*
Y03266D02*
X06336Y03267D01*
X0373Y00726D02*
Y00731D01*
X03368Y0305D02*
X03371D01*
X03372Y03051*
X03438*
X06347Y0325D02*
X06388D01*
X06343Y03246D02*
X06347Y0325D01*
X06302Y03246D02*
X06343D01*
X06282Y03226D02*
X06302Y03246D01*
X01897Y01516D02*
X02108Y01728D01*
X02141Y02624D02*
X02146D01*
X01631Y04024D02*
X01653D01*
X01658Y04019*
X01659*
X03484Y03051D02*
Y03094D01*
X03566Y03486D02*
X03622D01*
X03518Y03437D02*
X03566Y03486D01*
X0351Y03395D02*
X03518Y03403D01*
Y03437*
X03345Y02995D02*
X03444D01*
X03344Y02996D02*
X03345Y02995D01*
X06311Y03201D02*
X06331D01*
X06362Y03231D02*
X06388D01*
X06331Y03201D02*
X06362Y03231D01*
X06309Y03199D02*
X06311Y03201D01*
X03377Y03467D02*
X03403D01*
X03423Y03431D02*
Y03435D01*
X03414Y03444D02*
Y03455D01*
X03423Y03431D02*
X03428Y03426D01*
X03435D02*
X03451Y0341D01*
X03403Y03467D02*
X03414Y03455D01*
X03451Y03395D02*
Y0341D01*
X03428Y03426D02*
X03435D01*
X03414Y03444D02*
X03423Y03435D01*
X06447Y03396D02*
X06459Y03383D01*
Y03332D02*
Y03383D01*
X02829Y03655D02*
X02834Y03661D01*
X02829Y03645D02*
Y03655D01*
X02799Y03616D02*
X02829Y03645D01*
X03589Y01711D02*
X03591D01*
X00932Y00906D02*
X01004D01*
X00932Y01431D02*
X01007D01*
X01008Y0143*
X00932Y01956D02*
X01009D01*
X00932Y02481D02*
X0102D01*
X03469Y03653D02*
Y03661D01*
X03242Y03659D02*
X03244Y03661D01*
X03242Y03598D02*
Y03659D01*
X03239Y03596D02*
X03242Y03598D01*
X03529Y03481D02*
X0353Y03479D01*
X0268Y03661D02*
X02719D01*
X02679Y03661D02*
X0268Y03661D01*
X03701Y03752D02*
Y03786D01*
X03699Y03751D02*
X03701Y03752D01*
Y03837D02*
Y03861D01*
X03699Y03836D02*
X03701Y03837D01*
X03724Y01674D02*
X03724Y01675D01*
X06339Y03151D02*
X06341Y03152D01*
X06388*
X04707Y04121D02*
X04712Y04115D01*
X04754*
X05267Y04088D02*
Y04126D01*
X03772Y03683D02*
X03794D01*
X03799Y03687*
X038*
X03964Y03683D02*
X03987D01*
X0396Y03687D02*
X03964Y03683D01*
X03958Y03687D02*
X0396D01*
X03Y03701D02*
X03035Y03666D01*
X03044*
X0601Y02338D02*
X0604Y02369D01*
X06004Y02338D02*
X0601D01*
X0604Y02369D02*
X06056D01*
X06064Y02377*
X06459Y0315D02*
X0646Y0315D01*
Y03164*
X06469Y03173*
X06489*
X0644Y0315D02*
Y0319D01*
X06439Y03191D02*
X0644Y0319D01*
X06354Y03331D02*
X06356Y03329D01*
X06388*
X0642Y03332D02*
X06421Y03331D01*
Y03314D02*
Y03331D01*
Y03314D02*
X06444Y03291D01*
X06409Y03371D02*
X06424D01*
X0644Y03355*
Y03332D02*
Y03355D01*
X06479Y03425D02*
X06479Y03426D01*
X06509Y03456D02*
X06511Y03454D01*
Y03329D02*
Y03454D01*
X06479Y03332D02*
Y03425D01*
X02839Y03666D02*
X02944D01*
X02834Y03661D02*
X02839Y03666D01*
X03044Y03745D02*
Y03951D01*
X03144Y03666D02*
X03239D01*
X03244Y03661*
X03464Y03666D02*
X03469Y03661D01*
X03667Y03786D02*
X03668D01*
X03667Y03861D02*
X03668D01*
X03618Y03909D02*
X03667Y03861D01*
X03589Y03909D02*
X03618D01*
X03701Y03861D02*
X03702Y03859D01*
X03771*
X03772Y03858*
X03701Y03786D02*
X03702Y03784D01*
X03771*
X03772Y03783*
X00594Y00906D02*
X00932D01*
X00199D02*
X00594D01*
Y01431D02*
X00932D01*
X00199D02*
X00594D01*
Y01956D02*
X00932D01*
X00199D02*
X00594D01*
Y02481D02*
X00932D01*
X00199D02*
X00594D01*
X06939Y01889D02*
X07004D01*
X07009Y01883*
X06832Y01931D02*
X06931D01*
X06939Y01922*
X06832Y02031D02*
X06836D01*
X06843Y02038*
Y02096*
X06749Y02035D02*
Y02088D01*
Y02035D02*
X06804Y01981D01*
X06832*
X06481Y01954D02*
X06519D01*
X06369Y01842D02*
X06481Y01954D01*
X06319Y01842D02*
X06369D01*
X06542Y01931D02*
X06637D01*
X06519Y01953D02*
X06542Y01931D01*
X06519Y01953D02*
Y01954D01*
X06533Y02031D02*
X06637D01*
X06519Y02017D02*
X06533Y02031D01*
X06064Y02344D02*
X06067Y02341D01*
X06157*
X06156Y02171D02*
Y0224D01*
X06157Y02241*
X06352D02*
X06468D01*
X06469Y02239*
X06512Y03072D02*
X06584D01*
X0651Y03071D02*
X06512Y03072D01*
X0651Y03071D02*
Y03076D01*
X0646Y03126D02*
X0651Y03076D01*
X0646Y03126D02*
Y03149D01*
X06459Y0315D02*
X0646Y03149D01*
X01048Y04099D02*
Y04192D01*
X01042Y04093D02*
X01048Y04099D01*
X01249D02*
Y04192D01*
X01243Y04093D02*
X01249Y04099D01*
G54D21*
X02584Y00265D02*
D01*
X02584Y00266*
X02584Y00268*
X02584Y00269*
X02583Y0027*
X02583Y00272*
X02582Y00273*
X02582Y00274*
X02581Y00275*
X0258Y00277*
X02579Y00278*
X02578Y00279*
X02578Y00279*
X02905D02*
D01*
X02905Y00279*
X02905Y00279*
X02905Y00279*
X02905Y00279*
X02905Y00279*
Y00279*
D01*
X02904Y00278*
X02903Y00277*
X02902Y00276*
X02902Y00275*
X02901Y00273*
X029Y00272*
X029Y00271*
X029Y00269*
X02899Y00268*
X02899Y00266*
X02899Y00265*
X02899Y00265*
X02764Y00979D02*
D01*
X02764Y00979*
X02764Y00979*
X02764Y00979*
X02764Y00978*
X02764Y00978*
X02764Y00978*
X02764Y00978*
X02764Y00978*
X02764Y00977*
X02764Y00977*
X02765Y00977*
X02765Y00977*
X02765Y00977*
X02765Y00976*
X02765Y00976*
X02766Y00976*
X02766Y00976*
X02766Y00976*
X02766Y00976*
X02767Y00976*
X02767Y00976*
X02767Y00976*
X02767Y00976*
X02746Y00278D02*
D01*
X02745Y00277*
X02745Y00275*
X02744Y00274*
X02743Y00273*
X02743Y00272*
X02742Y0027*
X02742Y00269*
X02742Y00268*
X02742Y00266*
X02742Y00265*
X02742Y00265*
X02746Y00278D02*
D01*
X02747Y00278*
X02747Y00278*
X02747Y00279*
X02747Y00279*
X02747Y00279*
X02748Y00282D02*
D01*
X02748Y00281*
X02748Y00281*
X02748Y00281*
X027Y0083D02*
D01*
X02701Y00831*
X02702Y00832*
X02702Y00833*
X02703Y00833*
X02703Y00834*
X02704Y00835*
X02704Y00836*
X02704Y00837*
X02704Y00838*
X02705Y00839*
X02705Y0084*
X02705Y00841*
X027Y0083D02*
D01*
X02699Y00829*
X02698Y00827*
X02697Y00826*
X02696Y00824*
X02695Y00823*
X02694Y00821*
X02694Y00819*
X02693Y00817*
X02693Y00815*
X02693Y00814*
X02692Y00812*
X02692Y00811*
X0261Y00259D02*
D01*
X0261Y00257*
X0261Y00255*
X0261Y00253*
X02611Y00251*
X02611Y00249*
X02612Y00248*
X02613Y00246*
X02614Y00244*
X02615Y00243*
X02616Y00241*
X02617Y0024*
X02618Y0024*
X02624Y00225D02*
D01*
X02623Y00227*
X02623Y00228*
X02623Y0023*
X02623Y00231*
X02622Y00232*
X02622Y00234*
X02621Y00235*
X0262Y00236*
X0262Y00237*
X02619Y00238*
X02618Y00239*
X02618Y0024*
X02681Y0083D02*
D01*
X02681Y00831*
X02682Y00832*
X02683Y00833*
X02683Y00833*
X02684Y00834*
X02684Y00835*
X02684Y00836*
X02685Y00837*
X02685Y00838*
X02685Y00839*
X02685Y0084*
X02685Y00841*
X02679Y00828D02*
D01*
X02679Y00828*
X02679Y00828*
X02679Y00828*
X02679Y00828*
X02679Y00828*
D01*
X02677Y00826*
X02674Y00823*
X02673Y00821*
X02671Y00818*
X02669Y00815*
X02668Y00812*
X02667Y00809*
X02666Y00805*
X02665Y00802*
X02665Y00799*
X02665Y00796*
X02665Y00795*
X02882Y00822D02*
D01*
X02882Y0082*
X02882Y00817*
X02883Y00814*
X02883Y00812*
X02884Y00809*
X02885Y00806*
X02886Y00804*
X02888Y00802*
X02889Y00799*
X02891Y00797*
X02893Y00795*
X02893Y00795*
X02862D02*
D01*
X02862Y00795*
X02862Y00795*
X02862Y00795*
X02862Y00795*
X02862Y00795*
X02862Y00795*
X02862Y00795*
X02862Y00795*
X02862Y00796*
X02862Y00796*
X02862Y00796*
X02862Y00796*
X02781Y00274D02*
D01*
X02781Y00275*
X02781Y00275*
X02781Y00276*
X02781Y00276*
X02781Y00277*
X0278Y00277*
X0278Y00277*
X0278Y00278*
X0278Y00278*
X02779Y00279*
X02779Y00279*
X02779Y00279*
X02823Y00803D02*
D01*
X02823Y00802*
X02823Y00802*
X02823Y00801*
X02823Y008*
X02823Y00799*
X02824Y00798*
X02824Y00798*
X02825Y00797*
X02825Y00796*
X02826Y00796*
X02826Y00795*
X02826Y00795*
X02799D02*
D01*
X02799Y00796*
X028Y00796*
X02801Y00797*
X02801Y00798*
X02802Y00799*
X02802Y008*
X02802Y00801*
X02803Y00802*
X02803Y00803*
X02803Y00804*
X02803Y00805*
X02803Y00805*
X0274Y00819D02*
D01*
X02738Y00817*
X02737Y00816*
X02736Y00814*
X02735Y00812*
X02734Y00811*
X02734Y00809*
X02733Y00807*
X02732Y00805*
X02732Y00803*
X02732Y00802*
X02732Y008*
X02732Y00799*
X02759Y00795D02*
D01*
X0276Y00796*
X02761Y00796*
X02761Y00797*
X02762Y00798*
X02762Y00799*
X02763Y008*
X02763Y00801*
X02763Y00802*
X02763Y00803*
X02764Y00804*
X02764Y00805*
X02764Y00805*
X0274Y00819D02*
D01*
X0274Y00819*
X02741Y0082*
X02742Y00821*
X02742Y00822*
X02743Y00823*
X02743Y00824*
X02743Y00824*
X02744Y00825*
X02744Y00826*
X02744Y00827*
X02744Y00828*
X02744Y00829*
X02629Y00818D02*
D01*
X02632Y00821*
X02634Y00824*
X02637Y00827*
X02639Y00831*
X0264Y00834*
X02642Y00838*
X02643Y00841*
X02644Y00845*
X02645Y00849*
X02645Y00853*
X02646Y00856*
X02646Y00857*
X02629Y00818D02*
D01*
X02629Y00818*
X02628Y00817*
X02628Y00816*
X02627Y00815*
X02627Y00815*
X02626Y00814*
X02626Y00813*
X02626Y00812*
X02626Y00811*
X02626Y0081*
X02625Y00809*
X02625Y00809*
X02618Y00826D02*
D01*
X02619Y00828*
X0262Y00829*
X02621Y00831*
X02622Y00833*
X02623Y00834*
X02624Y00836*
X02625Y00838*
X02625Y0084*
X02626Y00842*
X02626Y00844*
X02626Y00846*
X02626Y00846*
X02606Y00815D02*
D01*
X02605Y00813*
X02604Y00812*
X02603Y0081*
X02602Y00809*
X02601Y00807*
X026Y00805*
X02599Y00803*
X02599Y00801*
X02598Y00799*
X02598Y00797*
X02598Y00795*
X02598Y00795*
X02938Y00274D02*
D01*
X02938Y00275*
X02938Y00275*
X02938Y00276*
X02938Y00276*
X02938Y00277*
X02938Y00277*
X02938Y00277*
X02937Y00278*
X02937Y00278*
X02937Y00279*
X02937Y00279*
X02937Y00279*
X0274Y00976D02*
D01*
X0274Y00976*
X0274Y00976*
X02741Y00976*
X02741Y00976*
X02741Y00976*
X02741Y00976*
X02742Y00976*
X02742Y00977*
X02742Y00977*
X02742Y00977*
X02743Y00977*
X02743Y00977*
X02743Y00978*
X02743Y00978*
X02743Y00978*
X02744Y00978*
X02744Y00979*
X02744Y00979*
X02744Y00979*
X02744Y00979*
X02744Y0098*
X02744Y0098*
X02744Y0098*
X02823Y00979D02*
D01*
X02823Y00979*
X02823Y00979*
X02823Y00979*
X02823Y00978*
X02823Y00978*
X02823Y00978*
X02823Y00978*
X02823Y00978*
X02823Y00977*
X02824Y00977*
X02824Y00977*
X02824Y00977*
X02824Y00977*
X02824Y00976*
X02824Y00976*
X02825Y00976*
X02825Y00976*
X02825Y00976*
X02825Y00976*
X02826Y00976*
X02826Y00976*
X02826Y00976*
X02826Y00976*
X02799D02*
D01*
X02799Y00976*
X02799Y00976*
X028Y00976*
X028Y00976*
X028Y00976*
X028Y00976*
X02801Y00976*
X02801Y00977*
X02801Y00977*
X02801Y00977*
X02802Y00977*
X02802Y00977*
X02802Y00978*
X02802Y00978*
X02802Y00978*
X02803Y00978*
X02803Y00979*
X02803Y00979*
X02803Y00979*
X02803Y00979*
X02803Y0098*
X02803Y0098*
X02803Y0098*
X02705Y00979D02*
D01*
X02705Y00979*
X02705Y00979*
X02705Y00979*
X02705Y00978*
X02705Y00978*
X02705Y00978*
X02705Y00978*
X02705Y00978*
X02705Y00977*
X02705Y00977*
X02706Y00977*
X02706Y00977*
X02706Y00977*
X02706Y00976*
X02706Y00976*
X02707Y00976*
X02707Y00976*
X02707Y00976*
X02707Y00976*
X02708Y00976*
X02708Y00976*
X02708Y00976*
X02708Y00976*
X02681D02*
D01*
X02681Y00976*
X02681Y00976*
X02681Y00976*
X02682Y00976*
X02682Y00976*
X02682Y00976*
X02683Y00976*
X02683Y00977*
X02683Y00977*
X02683Y00977*
X02684Y00977*
X02684Y00977*
X02684Y00978*
X02684Y00978*
X02684Y00978*
X02684Y00978*
X02685Y00979*
X02685Y00979*
X02685Y00979*
X02685Y00979*
X02685Y0098*
X02685Y0098*
X02685Y0098*
X02413Y00279D02*
D01*
X02409Y00275*
X02405Y0027*
X02401Y00265*
X02398Y0026*
X02395Y00254*
X02393Y00249*
X02391Y00243*
X0239Y00237*
X02388Y00231*
X02388Y00225*
X02387Y00219*
X02387Y00217*
X02646Y00979D02*
D01*
X02646Y00979*
X02646Y00979*
X02646Y00979*
X02646Y00978*
X02646Y00978*
X02646Y00978*
X02646Y00978*
X02646Y00978*
X02646Y00977*
X02646Y00977*
X02647Y00977*
X02647Y00977*
X02647Y00977*
X02647Y00976*
X02647Y00976*
X02648Y00976*
X02648Y00976*
X02648Y00976*
X02648Y00976*
X02648Y00976*
X02649Y00976*
X02649Y00976*
X02649Y00976*
X02444Y00279D02*
D01*
X02442Y00276*
X02439Y00273*
X02436Y00269*
X02434Y00266*
X02432Y00262*
X02431Y00258*
X02429Y00254*
X02428Y0025*
X02427Y00246*
X02427Y00242*
X02427Y00237*
X02427Y00236*
X02622Y00976D02*
D01*
X02622Y00976*
X02622Y00976*
X02622Y00976*
X02623Y00976*
X02623Y00976*
X02623Y00976*
X02624Y00976*
X02624Y00977*
X02624Y00977*
X02624Y00977*
X02625Y00977*
X02625Y00977*
X02625Y00978*
X02625Y00978*
X02625Y00978*
X02625Y00978*
X02626Y00979*
X02626Y00979*
X02626Y00979*
X02626Y00979*
X02626Y0098*
X02626Y0098*
X02626Y0098*
X02781Y00112D02*
D01*
X02781Y00112*
X02781Y00111*
X02781Y00111*
X02781Y00111*
X02781Y00111*
X02781Y00111*
X02782Y00111*
X02782Y00111*
X02782Y00111*
X02782Y00111*
X02782Y00111*
X02782Y00111*
X02772Y00133D02*
D01*
X02772Y00131*
X02773Y00129*
X02773Y00127*
X02774Y00124*
X02774Y00122*
X02775Y0012*
X02776Y00118*
X02777Y00116*
X02778Y00114*
X0278Y00113*
X02781Y00111*
X02782Y00111*
X02612Y00139D02*
D01*
X02612Y00137*
X02613Y00134*
X02613Y00131*
X02614Y00128*
X02615Y00125*
X02616Y00123*
X02617Y0012*
X02619Y00118*
X0262Y00115*
X02622Y00113*
X02624Y00111*
X02624Y00111*
X02575Y00134D02*
D01*
X02575Y00131*
X02576Y00129*
X02576Y00127*
X02577Y00125*
X02577Y00123*
X02578Y0012*
X02579Y00118*
X0258Y00116*
X02582Y00114*
X02583Y00113*
X02585Y00111*
X02585Y00111*
X02418Y00133D02*
D01*
X02418Y0013*
X02419Y00128*
X02419Y00126*
X0242Y00124*
X0242Y00122*
X02421Y0012*
X02422Y00118*
X02423Y00116*
X02424Y00114*
X02426Y00113*
X02427Y00111*
X02427Y00111*
X0261Y00259D02*
Y00279D01*
X02905Y00279D02*
X02905Y00279D01*
X02899Y00137D02*
Y00265D01*
X02764Y00979D02*
Y01038D01*
X02746Y00278D02*
X02746Y00278D01*
X02747Y00279D02*
X02748Y00281D01*
X02748Y00282D02*
X02748Y00282D01*
X02748Y00282*
X02862Y00796D02*
Y00878D01*
X02764Y00805D02*
Y00878D01*
X02781Y00137D02*
Y00274D01*
X02803Y00805D02*
Y00878D01*
X02742Y00137D02*
Y00265D01*
X02823Y00803D02*
Y00878D01*
X02584Y00137D02*
Y00265D01*
X02899Y00137D02*
D01*
X02705Y00841D02*
Y00878D01*
X02692Y00795D02*
Y00811D01*
X02624Y00137D02*
Y00225D01*
X02685Y00841D02*
Y00878D01*
X02679Y00828D02*
X02681Y0083D01*
X02679Y00828D02*
Y00828D01*
X02882Y00822D02*
Y00878D01*
X02732Y00799D02*
Y00799D01*
X02744Y00829D02*
Y00878D01*
X02732Y00795D02*
Y00799D01*
X02625Y00795D02*
Y00809D01*
X02606Y00815D02*
X02618Y00826D01*
X02646Y00857D02*
Y00878D01*
X02626Y00846D02*
Y00878D01*
X02938Y00137D02*
Y00274D01*
X02744Y0098D02*
Y01038D01*
X02823Y00979D02*
Y01038D01*
X02803D02*
X02803Y01038D01*
X02803Y0098D02*
Y01038D01*
X02705Y00979D02*
Y01038D01*
X02685Y0098D02*
Y01038D01*
X02387Y00137D02*
Y00217D01*
X02646Y00979D02*
Y01038D01*
X02427Y00137D02*
Y00236D01*
X02626Y0098D02*
Y01038D01*
X02742Y00111D02*
X02745Y00113D01*
X0274Y00113D02*
X02742Y00111D01*
X02931Y00118D02*
X02939Y00111D01*
X029D02*
X02907Y00118D01*
G54D24*
X06605Y03129D02*
X06647D01*
X06604Y03129D02*
X06605Y03129D01*
X06487Y03125D02*
X06551D01*
X06479Y03132D02*
X06487Y03125D01*
X06479Y03132D02*
Y03143D01*
X06555Y03129D02*
X06604D01*
X06551Y03125D02*
X06555Y03129D01*
X06479Y03143D02*
X06479Y03143D01*
G54D26*
X02756Y03287D03*
Y03237D03*
Y03187D03*
Y03137D03*
Y03087D03*
Y03037D03*
Y02987D03*
Y02937D03*
X03111Y03287D03*
Y03237D03*
Y03187D03*
Y03137D03*
Y03087D03*
Y03037D03*
Y02987D03*
Y02937D03*
G54D27*
X02271Y04275D03*
G54D28*
X02377Y04275D03*
G54D29*
X02234Y04173D03*
X0243D03*
G54D30*
X02383Y0417D03*
X02358D03*
X02332D03*
X02306D03*
X02281D03*
G54D31*
X02465Y04275D03*
X02199D03*
G54D32*
X04046Y04244D03*
Y04027D03*
X03696D03*
Y04244D03*
G54D33*
X03934Y04023D03*
X03902D03*
X03871D03*
X03839D03*
X03808D03*
G54D34*
X00594Y00906D03*
Y01956D03*
Y02481D03*
Y01431D03*
G54D35*
X00654Y00964D03*
Y00847D03*
Y01897D03*
Y02014D03*
Y02422D03*
Y02539D03*
Y01489D03*
Y01372D03*
G54D36*
X03469Y03661D03*
X03444Y0375D03*
X03495D03*
X02834Y03661D03*
X02809Y0375D03*
X0286D03*
X02719Y03661D03*
X02694Y0375D03*
X02745D03*
X03244Y03661D03*
X03219Y0375D03*
X0327D03*
G54D37*
X01846Y04024D03*
Y04049D03*
Y04074D03*
Y04099D03*
Y04124D03*
Y04149D03*
Y04174D03*
Y04199D03*
X01631Y04024D03*
Y04049D03*
Y04074D03*
Y04099D03*
Y04124D03*
Y04149D03*
Y04174D03*
Y04199D03*
X03987Y03683D03*
Y03708D03*
Y03733D03*
Y03758D03*
Y03783D03*
Y03808D03*
Y03833D03*
Y03858D03*
X03772Y03683D03*
Y03708D03*
Y03733D03*
Y03758D03*
Y03783D03*
Y03808D03*
Y03833D03*
Y03858D03*
G54D38*
X06352Y02241D03*
Y02291D03*
Y02341D03*
Y02391D03*
X06157D03*
Y02341D03*
Y02291D03*
Y02241D03*
X06637Y02031D03*
Y01981D03*
Y01931D03*
Y01881D03*
X06832D03*
Y01931D03*
Y01981D03*
Y02031D03*
G54D39*
X06341Y03701D03*
X06197D03*
X06031D03*
X05887D03*
X06202Y03566D03*
X06346D03*
G54D40*
X06726Y03168D03*
X06943D03*
Y03294D03*
X06726D03*
G54D41*
X03451Y03206D03*
X03392D03*
X03451Y03395D03*
X0351D03*
X03569Y03206D03*
X03333Y03395D03*
Y03206D03*
X0351D03*
X03392Y03395D03*
G54D42*
X03569Y03385D03*
G54D43*
X03438Y03051D03*
Y02892D03*
X03531Y03051D03*
Y02892D03*
G54D44*
X03484Y02892D03*
Y03051D03*
G54D45*
X03444Y02995D03*
Y02948D03*
X03525D03*
Y02995D03*
G54D46*
X03344Y04221D03*
Y03951D03*
X03244Y04221D03*
Y03951D03*
X03144Y04221D03*
Y03951D03*
X03044Y04221D03*
Y03951D03*
X02944Y04221D03*
Y03951D03*
G54D47*
X03349Y03666D03*
Y03745D03*
X02944Y03666D03*
Y03745D03*
X03044Y03666D03*
Y03745D03*
X03144Y03666D03*
Y03745D03*
G54D48*
X03477Y02797D03*
X03532D03*
X06035Y03556D03*
X0609D03*
X0415Y03603D03*
X04204D03*
X06897Y01816D03*
X06842D03*
X06782D03*
X06727D03*
X06367Y02451D03*
X06312D03*
X04167Y03701D03*
X04112D03*
X04652Y04206D03*
X04707D03*
X05212D03*
X05267D03*
X04652Y04121D03*
X04707D03*
X05267Y04126D03*
X05212D03*
G54D49*
X03701Y03786D03*
X03668D03*
X03701Y03861D03*
X03668D03*
G54D50*
X02545Y00137D03*
X02466D03*
X02348D03*
X0282D03*
X01915D03*
X02033D03*
X02663D03*
X02702D03*
X0286D03*
X02978D03*
X0219D03*
X01994D03*
X01954D03*
X03017D03*
X02309D03*
X02112D03*
X02151D03*
X02387D03*
X02427D03*
X02584D03*
X02624D03*
X02742D03*
X02781D03*
X02899D03*
X02938D03*
X02505D03*
X02072D03*
X01797D03*
X01836D03*
X01875D03*
X03096D03*
G54D51*
X03057Y00157D03*
G54D52*
X04957Y04206D03*
X05091D03*
X04432D03*
X04566D03*
G54D53*
X04068Y01599D03*
X03911D03*
Y01619D03*
X04068D03*
X03911Y01639D03*
X04068D03*
X03911Y01659D03*
X04068D03*
X03911Y01679D03*
X04068D03*
X03911Y01699D03*
X04068D03*
X03911Y01719D03*
X04068D03*
X03911Y01739D03*
X04068D03*
X03911Y01759D03*
X04068D03*
X03911Y01779D03*
X04068D03*
G54D54*
X06511Y03191D03*
Y03172D03*
Y03211D03*
Y03231D03*
Y0325D03*
Y0327D03*
Y0329D03*
Y03309D03*
Y03329D03*
X06388D03*
Y03309D03*
Y0329D03*
Y0327D03*
Y0325D03*
Y03231D03*
Y03211D03*
Y03191D03*
Y03172D03*
Y03152D03*
X06511D03*
G54D55*
X06479Y03332D03*
X06459D03*
X0644D03*
X0642D03*
Y0315D03*
X0644D03*
X06459D03*
X06479D03*
G54D56*
X00901Y00718D03*
X0096D03*
X00908Y02284D03*
X00967D03*
X009Y01747D03*
X00959D03*
X00904Y01224D03*
X00963D03*
G54D57*
X04149Y02789D03*
Y02842D03*
X04434Y02789D03*
Y02842D03*
G54D58*
X06679Y0242D03*
Y02802D03*
X06319Y01842D03*
Y0146D03*
G54D59*
X04909Y03961D03*
Y02808D03*
G54D60*
X01157Y00906D03*
X00932D03*
Y01956D03*
X01157D03*
X00932Y02481D03*
X01157D03*
Y01431D03*
X00932D03*
G54D61*
X01249Y04254D03*
Y04197D03*
X03589Y03852D03*
Y03909D03*
Y03784D03*
Y03727D03*
X00644Y04197D03*
Y04254D03*
X00846Y04197D03*
Y04254D03*
X01048D03*
Y04197D03*
G54D62*
X04339Y0278D03*
Y02851D03*
X06334Y0211D03*
Y02181D03*
X06659Y02166D03*
Y02095D03*
X06253Y02826D03*
Y02755D03*
X06372Y02826D03*
Y02755D03*
X04104Y0377D03*
Y03841D03*
X02209Y03716D03*
Y03645D03*
X02639Y03535D03*
Y03606D03*
X03693Y03188D03*
Y03117D03*
X04064Y0278D03*
Y02851D03*
X03959Y0278D03*
Y02851D03*
X04234Y0278D03*
Y02851D03*
G54D63*
X04039Y03029D03*
Y03092D03*
X06469Y02239D03*
Y02302D03*
X06519Y01954D03*
Y02017D03*
X04194Y03774D03*
Y03837D03*
X03688Y03266D03*
Y03329D03*
X06604Y03264D03*
Y03327D03*
Y03192D03*
Y03129D03*
G54D64*
X04109Y03044D03*
Y03077D03*
X06939Y01889D03*
Y01922D03*
X06064Y02344D03*
Y02377D03*
X06584Y03039D03*
Y03072D03*
X02139Y03697D03*
Y03664D03*
X02724Y03559D03*
Y03592D03*
X03769Y03234D03*
Y03201D03*
X04454Y03044D03*
Y03077D03*
X04394Y03044D03*
Y03077D03*
X04334Y03044D03*
Y03077D03*
X04274Y03044D03*
Y03077D03*
X04219Y03044D03*
Y03077D03*
X04164Y03044D03*
Y03077D03*
G54D65*
X03269Y02834D03*
Y02814D03*
Y02795D03*
X03209D03*
Y02814D03*
Y02834D03*
G54D66*
X03249Y02784D03*
X03229D03*
Y02845D03*
X03249D03*
G54D67*
X03492Y01398D03*
Y01378D03*
Y01457D03*
Y01477D03*
Y01772D03*
Y01496D03*
Y01792D03*
Y0189D03*
Y01851D03*
Y0187D03*
Y01831D03*
X03651Y0187D03*
Y0189D03*
Y01929D03*
X03492Y01339D03*
Y01359D03*
X03651Y01792D03*
Y01772D03*
Y01851D03*
Y01831D03*
Y01949D03*
Y01988D03*
Y01969D03*
X03492Y01988D03*
Y01969D03*
X03651Y01693D03*
X03492Y01634D03*
Y01673D03*
Y01654D03*
Y01693D03*
X03651Y01733D03*
Y01752D03*
Y01654D03*
Y01575D03*
Y01555D03*
Y01673D03*
Y01634D03*
X03492Y01929D03*
Y01555D03*
Y02008D03*
Y0191D03*
Y01811D03*
Y01713D03*
Y01614D03*
Y01516D03*
Y01418D03*
X03651Y02008D03*
Y0191D03*
Y01811D03*
Y01713D03*
Y01614D03*
Y01516D03*
Y01418D03*
X03492Y01949D03*
X03651Y01595D03*
X03492Y01536D03*
X03651Y01496D03*
Y01477D03*
Y01457D03*
Y01437D03*
Y01398D03*
Y01378D03*
Y01359D03*
Y01339D03*
X03492Y01319D03*
X03651D03*
X03492Y01733D03*
Y01752D03*
X03651Y01536D03*
X03492Y01575D03*
Y01595D03*
Y01437D03*
Y02087D03*
Y02067D03*
Y02047D03*
Y02028D03*
X03651Y02087D03*
Y02067D03*
Y02047D03*
Y02028D03*
X01776Y01634D03*
Y01614D03*
Y0187D03*
Y02028D03*
Y0191D03*
Y01831D03*
Y01949D03*
Y01733D03*
Y01772D03*
X01617Y01929D03*
Y01851D03*
Y0191D03*
Y02028D03*
X01776Y02008D03*
Y01969D03*
Y01457D03*
Y01674D03*
X01617Y0187D03*
Y01969D03*
X01776Y01929D03*
Y01851D03*
Y01811D03*
Y01654D03*
X01617Y02008D03*
X01776Y01752D03*
Y01713D03*
X01617Y01949D03*
X01776Y01555D03*
Y01575D03*
X01617Y01516D03*
Y01457D03*
Y01811D03*
Y01831D03*
X01776Y01437D03*
X01617Y01359D03*
X01776Y01339D03*
X01617Y01575D03*
Y01437D03*
Y01536D03*
Y01555D03*
Y01614D03*
Y01733D03*
Y01674D03*
Y01378D03*
Y01477D03*
Y01418D03*
Y01752D03*
X01776Y01359D03*
X01617Y01339D03*
Y01634D03*
Y01772D03*
X01776Y01378D03*
Y01319D03*
Y01418D03*
X01617Y01319D03*
X01776Y01477D03*
X01617Y01713D03*
Y01654D03*
X01776Y01516D03*
X01617Y02048D03*
X01776D03*
Y01398D03*
Y01496D03*
Y01595D03*
Y01693D03*
Y01792D03*
Y0189D03*
Y01988D03*
X01617Y01398D03*
Y01496D03*
Y01595D03*
Y01693D03*
Y01792D03*
Y0189D03*
Y01988D03*
Y02087D03*
X01776D03*
Y02067D03*
Y01536D03*
X01617Y02067D03*
G54D68*
X03571Y02131D03*
Y01275D03*
X01696Y01275D03*
Y02131D03*
G54D69*
X0298Y02518D03*
Y02358D03*
X02882Y02518D03*
X02783D03*
X02685D03*
X02586D03*
X02488D03*
X0239D03*
X02291D03*
X02882Y02358D03*
X02783D03*
X02685D03*
X02586D03*
X02488D03*
X0239D03*
X02291D03*
X02941D03*
X02961D03*
X02901D03*
X02921D03*
X02842D03*
X02862D03*
X02803D03*
X02823D03*
X02744D03*
X02764D03*
X02705D03*
X02724D03*
X02646D03*
X02665D03*
X02606D03*
X02626D03*
X02547D03*
X02567D03*
X02508D03*
X02527D03*
X02449D03*
X02468D03*
X02409D03*
X02429D03*
X0235D03*
X0237D03*
X02212Y02518D03*
X02232D03*
Y02358D03*
X02212D03*
X02252Y02518D03*
X02272D03*
X02409D03*
X02429D03*
X0235D03*
X0237D03*
X02508D03*
X02527D03*
X02449D03*
X02468D03*
X02606D03*
X02547D03*
X02626D03*
X02567D03*
X02705D03*
X02724D03*
X02646D03*
X02665D03*
X02803D03*
X02823D03*
X02744D03*
X02764D03*
X02901D03*
X02921D03*
X02842D03*
X02862D03*
X02941D03*
X02961D03*
X02252Y02358D03*
X02311D03*
X02331D03*
X02272D03*
X02311Y02518D03*
X02331D03*
X02803Y01038D03*
X02823D03*
X02862Y00878D03*
X02882D03*
X02744D03*
X02764D03*
X02685Y01038D03*
X02705D03*
X02587Y00878D03*
Y01038D03*
X02646Y00878D03*
X02626D03*
X02744Y01038D03*
X02764D03*
X02803Y00878D03*
X02823D03*
X02685D03*
X02705D03*
X02626Y01038D03*
X02646D03*
X02232Y00878D03*
X02429D03*
X0237D03*
X0235D03*
X02331D03*
X02291D03*
X0239D03*
X02488D03*
X02527D03*
X02547D03*
X02567D03*
X02449D03*
X02468D03*
X02252D03*
X02272D03*
X02567Y01038D03*
X0237D03*
X0239D03*
X02429D03*
X02468D03*
X02488D03*
X02449D03*
X02291D03*
X02272D03*
X02252D03*
X02232D03*
X0235D03*
X02331D03*
X02547D03*
X02527D03*
X02862D03*
X02882D03*
X02921Y00878D03*
Y01038D03*
X02941Y00878D03*
Y01038D03*
X0298Y00878D03*
Y01038D03*
X02961D03*
Y00878D03*
X02901Y01038D03*
X02842D03*
X02783D03*
X02724D03*
X02665D03*
X02606D03*
X02508D03*
X02409D03*
X02311D03*
X02901Y00878D03*
X02842D03*
X02783D03*
X02724D03*
X02665D03*
X02606D03*
X02508D03*
X02409D03*
X02311D03*
X02212D03*
Y01038D03*
G54D70*
X02168Y02438D03*
X02168Y00958D03*
X03024D03*
X03024Y02438D03*
G54D71*
X05741Y03361D03*
X05812D03*
X06629Y01421D03*
X067D03*
X06629Y01531D03*
X067D03*
X06439Y03071D03*
X0651D03*
X0373Y00726D03*
X03659D03*
X01802Y04276D03*
X01873D03*
X0428Y03246D03*
X04209D03*
G54D72*
X05634Y03359D03*
X05668D03*
X06327Y02656D03*
X06361D03*
X06327Y02501D03*
X06361D03*
X06327Y02556D03*
X06361D03*
X06327Y02611D03*
X06361D03*
X06676Y01611D03*
X06642D03*
X06676Y01671D03*
X06642D03*
X06676Y01721D03*
X06642D03*
X06676Y01776D03*
X06642D03*
X03716Y00636D03*
X03682D03*
G54D73*
X06906Y02096D03*
X06843D03*
X06093Y02171D03*
X06156D03*
X01664Y04273D03*
X01727D03*
G54D74*
X04275Y03603D03*
X04332D03*
G54D75*
X06749Y02143D03*
Y02088D03*
X06234Y02183D03*
Y02128D03*
X07009Y01883D03*
Y01938D03*
X06004Y02393D03*
Y02338D03*
X02146Y02624D03*
Y02679D03*
X00638Y04038D03*
Y04093D03*
X0084D03*
Y04038D03*
X01042Y04093D03*
Y04038D03*
X01243Y04093D03*
Y04038D03*
X06122Y02488D03*
Y02433D03*
X01933Y04074D03*
Y04129D03*
G54D76*
X02503Y00607D03*
Y00573D03*
X03055Y00607D03*
Y00573D03*
G54D77*
X02334Y03404D03*
Y03483D03*
Y03562D03*
Y0364D03*
X02509Y03404D03*
Y03562D03*
Y03483D03*
Y0364D03*
G54D78*
X01346Y04082D03*
Y04141D03*
Y04037D03*
Y03978D03*
X02151Y04015D03*
Y04074D03*
X02212Y04015D03*
Y04074D03*
X02387Y02899D03*
Y02958D03*
G54D143*
X00299Y01006D03*
Y00806D03*
X00099D03*
Y01006D03*
X00299Y02581D03*
Y02381D03*
X00099D03*
Y02581D03*
X00299Y02056D03*
Y01856D03*
X00099D03*
Y02056D03*
X00299Y01531D03*
Y01331D03*
X00099D03*
Y01531D03*
G54D153*
X02974Y00224D02*
D01*
X02974Y00226*
X02974Y00227*
X02974Y00228*
X02973Y0023*
X02973Y00231*
X02972Y00232*
X02972Y00234*
X02971Y00235*
X0297Y00236*
X02969Y00237*
X02969Y00237*
X02467Y00217D02*
D01*
X02467Y00218*
X02467Y0022*
X02466Y00221*
X02466Y00222*
X02466Y00224*
X02465Y00225*
X02464Y00226*
X02464Y00227*
X02463Y00229*
X02462Y0023*
X02461Y00231*
X0246Y00232*
X02459Y00233*
X02459Y00233*
X02957Y00251D02*
X02969Y00237D01*
X02974Y00141D02*
Y00224D01*
D01*
X02467Y00111D02*
Y00217D01*
D01*
X02447Y00242D02*
X02459Y00233D01*
X03097Y00111D02*
X03097Y00111D01*
Y00251*
X02636Y00247D02*
X0269D01*
X02637Y00247D02*
X02651D01*
X02636Y00247D02*
X02637Y00247D01*
X02702Y0018D02*
X02703Y00179D01*
X0269Y00247D02*
X02702Y00236D01*
X02703Y00111D02*
Y00179D01*
X02975Y00141D02*
X02978Y00137D01*
X02974Y00141D02*
X02975Y00141D01*
X06346Y03566D02*
X06381D01*
X06414Y03599*
Y03726*
X06565Y03802D02*
X06569Y03806D01*
X0649Y03802D02*
X06565D01*
X06414Y03726D02*
X0649Y03802D01*
X02545Y00244D02*
X02546Y00244D01*
X02545Y00111D02*
Y00244D01*
X01815Y00257D02*
X01835D01*
X02856Y00141D02*
Y00233D01*
X02347Y00112D02*
X02349Y00111D01*
X02837Y00251D02*
X02856Y00233D01*
X02347Y00112D02*
Y00237D01*
X02034Y00111D02*
Y00245D01*
X02817Y00141D02*
X0282Y00137D01*
X02817Y00141D02*
Y00233D01*
X02338Y00246D02*
X02347Y00237D01*
X02651Y00247D02*
X02663Y00235D01*
X02702Y00138D02*
X02702Y00137D01*
X02702Y00138D02*
Y0018D01*
X02663Y00137D02*
Y00235D01*
X02034Y00245D02*
X02034Y00246D01*
X02309D02*
X02338D01*
X02857Y00141D02*
X0286Y00137D01*
X02856Y00141D02*
X02857Y00141D01*
X02799Y00251D02*
X02837D01*
X02702Y0018D02*
Y00236D01*
X02799Y00251D02*
X02817Y00233D01*
X01915Y00111D02*
Y00244D01*
Y00111D02*
X01916Y00111D01*
X02073D02*
X02076Y00114D01*
X03466Y03806D02*
X03539D01*
X03444Y0375D02*
Y03783D01*
X03466Y03806*
X03589Y03784D02*
Y03827D01*
X0354Y03806D02*
X03569D01*
X03589Y03827*
Y03852*
X0354Y03806D02*
X0354Y03806D01*
X03539Y03806D02*
X0354Y03806D01*
Y03715D02*
Y03806D01*
X03219Y0375D02*
Y03826D01*
X0354Y03715D02*
X03654Y03601D01*
X04331Y03604D02*
X04332Y03603D01*
X04331Y03604D02*
Y03631D01*
X0431Y03653D02*
X04331Y03631D01*
X04057Y03601D02*
X04109Y03653D01*
X0431*
X03654Y03601D02*
X04057D01*
X04332Y03603D02*
X04677D01*
X04768Y03511*
X05274*
X02321Y03397D02*
X02329Y03406D01*
X02321Y03361D02*
Y03397D01*
X05274Y03511D02*
X05274Y03511D01*
X0588Y03701D02*
X05887Y03708D01*
X05722Y03783D02*
Y03844D01*
X06094Y03554D02*
Y03565D01*
X05725Y04033D02*
X05829Y04137D01*
X05812Y03302D02*
X05847D01*
X05655D02*
X05812D01*
X05636Y0332D02*
Y03357D01*
Y0332D02*
X05655Y03302D01*
X05636Y03357D02*
X05636Y03357D01*
X06744Y02143D02*
X0675Y02148D01*
X06293Y02181D02*
X06424D01*
X05994Y03449D02*
Y03552D01*
X05847Y03302D02*
X05994Y03449D01*
X062Y03568D02*
X06202Y03566D01*
X062Y03568D02*
Y03586D01*
X06197Y03588D02*
Y03701D01*
Y03588D02*
X062Y03586D01*
X06734Y03806D02*
X069D01*
X06569D02*
X06734D01*
X02084Y00271D02*
X02112D01*
X02072Y00259D02*
X02084Y00271D01*
X02072Y00137D02*
Y00259D01*
X01876Y00111D02*
Y0024D01*
X01846Y00267D02*
X01849D01*
X01837Y00111D02*
Y00255D01*
X01798Y00111D02*
Y00239D01*
X01815Y00257*
X01837Y00255D02*
X01849Y00267D01*
X01835Y00257D02*
X01846Y00267D01*
X06364Y0133D02*
X06667D01*
X06319Y01375D02*
X06364Y0133D01*
X06319Y01375D02*
Y0146D01*
X067Y01363D02*
Y01421D01*
X06667Y0133D02*
X067Y01363D01*
X06712Y02001D02*
Y02114D01*
X06691Y01981D02*
X06712Y02001D01*
X06637Y01981D02*
X06691D01*
X06712Y02135D02*
X0672Y02143D01*
X06712Y02114D02*
Y02135D01*
X067Y02102D02*
X06712Y02114D01*
X06666Y02102D02*
X067D01*
X06659Y02095D02*
X06666Y02102D01*
X0672Y02143D02*
X06744D01*
X06749*
X0671Y0222D02*
X0675Y02181D01*
Y02148D02*
Y02181D01*
X06587Y0222D02*
X0671D01*
X06547Y02181D02*
X06587Y0222D01*
X06281Y02149D02*
Y02192D01*
X06264Y02133D02*
X06281Y02149D01*
X06239Y02133D02*
X06264D01*
X06234Y02128D02*
X06239Y02133D01*
X06281Y02192D02*
X06293Y02181D01*
X06281Y02192D02*
Y02271D01*
X063Y02291*
X06352*
X06372Y02826D02*
Y02909D01*
X06253Y02826D02*
Y02909D01*
X0649Y02791D02*
X06669D01*
X06454Y02755D02*
X0649Y02791D01*
X06372Y02755D02*
X06454D01*
X06669Y02791D02*
X06679Y02802D01*
X06253Y02755D02*
X06372D01*
X06253Y02673D02*
Y02755D01*
X06271Y02656D02*
X06327D01*
X06253Y02673D02*
X06271Y02656D01*
X06199Y02501D02*
X06284D01*
X06187Y02488D02*
X06199Y02501D01*
X06122Y02488D02*
X06187D01*
X06549Y02929D02*
X06639D01*
X0651Y02968D02*
X06549Y02929D01*
X0651Y02968D02*
Y03071D01*
X06679Y02802D02*
Y02889D01*
X06639Y02929D02*
X06679Y02889D01*
X062Y03708D02*
X06226D01*
X06197Y03705D02*
X062Y03708D01*
X06197Y03701D02*
Y03705D01*
X06226Y03708D02*
X06253Y03736D01*
Y0409*
X06207Y04137D02*
X06253Y0409D01*
X05829Y04137D02*
X06207D01*
X06094Y03554D02*
X0615D01*
X06162Y03566*
X06202*
X06119Y03743D02*
Y03819D01*
X06077Y03701D02*
X06119Y03743D01*
X06031Y03701D02*
X06077D01*
X05804D02*
X0588D01*
X05722Y03783D02*
X05804Y03701D01*
X05299Y03537D02*
Y04196D01*
X05289Y04206D02*
X05299Y04196D01*
X05267Y04206D02*
X05289D01*
X05267D02*
Y04255D01*
X05246Y04276D02*
X05267Y04255D01*
X04777Y04276D02*
X05246D01*
X04334Y03044D02*
X04394D01*
X04274D02*
X04334D01*
X04164D02*
X04219D01*
X04109D02*
X04164D01*
X04074Y02842D02*
X04149D01*
X04064Y02851D02*
X04074Y02842D01*
X04149Y02789D02*
X0415Y0279D01*
X04176*
X04187Y02801*
Y0282*
X04206Y02838*
X04222*
X04234Y02851*
X04339D02*
X04391D01*
X04401Y02842*
X04434*
X05887Y03701D02*
Y03708D01*
X05998Y03556D02*
X06035D01*
X05994Y03552D02*
X05998Y03556D01*
X0609Y03561D02*
X06094Y03565D01*
X0609Y03556D02*
Y03561D01*
X04234Y02851D02*
X04339D01*
X02724Y03521D02*
Y03559D01*
X02674Y03501D02*
Y03506D01*
X02639Y03535D02*
X02645D01*
X02674Y03506*
X04234Y02725D02*
Y0278D01*
X04339Y02725D02*
Y0278D01*
X04394Y03044D02*
X04454D01*
X04219D02*
X04274D01*
X03812Y03291D02*
X03969Y03133D01*
X02139Y03663D02*
Y03664D01*
Y03611D02*
Y03663D01*
X02209Y03645D02*
X02211Y03643D01*
X02328*
X02329Y03642*
X02139Y03663D02*
X02157Y03645D01*
X02209*
X01249Y04254D02*
X01293D01*
X01294Y04256*
X03969Y03098D02*
X04029Y03039D01*
X04031*
X04039Y0303*
X03732Y03291D02*
X03812D01*
X03702Y03261D02*
X03732Y03291D01*
X04039Y03029D02*
Y0303D01*
X03969Y03098D02*
Y03133D01*
X04454Y03044D02*
X04457Y03046D01*
X04474*
X04539Y03111*
X04449Y03246D02*
X04539Y03156D01*
X0428Y03246D02*
X04449D01*
X04039Y03029D02*
X04096D01*
X04109Y03043*
Y03044*
X03959Y02851D02*
Y02948D01*
X04039Y03028*
Y03029*
X03959Y02851D02*
X04064D01*
X04434Y02789D02*
X04503D01*
X05274Y03512D02*
X05299Y03537D01*
X05274Y03511D02*
Y03512D01*
X04707Y04206D02*
Y04211D01*
X04711Y04215*
X04716*
X04777Y04276*
X06284Y02501D02*
X06327D01*
X02724Y03592D02*
X02727Y0359D01*
X0275*
X02774Y03566*
X02633Y03606D02*
X02639D01*
X02598Y03642D02*
X02633Y03606D01*
X02504Y03642D02*
X02598D01*
X02659Y03592D02*
X02724D01*
X02645Y03606D02*
X02659Y03592D01*
X02639Y03606D02*
X02645D01*
X04253Y03774D02*
X04254Y03776D01*
X06842Y0181D02*
Y01816D01*
Y01668D02*
Y0181D01*
X06844Y01661D02*
Y01666D01*
X06842Y01668D02*
X06844Y01666D01*
X06424Y02181D02*
X06547D01*
X06424Y02181D02*
X06424Y02181D01*
X02139Y03664D02*
X02142Y03666D01*
X01048Y04254D02*
X01249D01*
X00846D02*
X01048D01*
X00644D02*
X00846D01*
X03189Y03855D02*
Y04101D01*
Y03855D02*
X03219Y03826D01*
X03144Y04146D02*
Y04221D01*
Y04146D02*
X03189Y04101D01*
X02694Y0375D02*
Y03757D01*
X02722Y03786*
X02781*
X02809Y03757*
Y0375D02*
Y03757D01*
X03044Y04221D02*
X03144D01*
X06327Y02611D02*
Y02656D01*
Y02556D02*
Y02611D01*
Y02501D02*
Y02556D01*
X06294Y03701D02*
X06341D01*
X06676Y01776D02*
X06808D01*
X06842Y0181*
X06676Y01721D02*
Y01776D01*
Y01671D02*
Y01721D01*
Y01611D02*
Y01671D01*
X067Y01531D02*
Y01536D01*
X06676Y0156D02*
X067Y01536D01*
X06676Y0156D02*
Y01611D01*
X067Y01421D02*
Y01531D01*
G54D154*
X02112Y00269D03*
G54D155*
X01836Y00269D03*
G54D156*
X03958Y04126D03*
X03784D03*
G54D157*
X03294Y04086D03*
X02994D03*
G54D158*
X05327Y02307D03*
X05127D03*
X04927D03*
X04727D03*
X04927Y01007D03*
X05127D03*
X04327Y02307D03*
X05327Y01007D03*
G54D159*
X04327Y01007D03*
G54D160*
X05578Y0089D03*
Y01689D03*
Y02489D03*
X03979D03*
Y0089D03*
X04062Y02595D03*
X0418D03*
X04298D03*
G54D161*
X05723Y04025D03*
Y03844D03*
X069Y03806D03*
Y03589D03*
X06734D03*
Y03806D03*
X06569Y03589D03*
Y03806D03*
G54D162*
X05934Y03937D03*
G54D163*
X06119Y04056D03*
G54D164*
X06119Y03819D03*
G54D165*
X00199Y00906D03*
Y02481D03*
Y01956D03*
Y01431D03*
G54D166*
X03571Y02097D03*
Y01309D03*
X02203Y02438D03*
X01696Y01309D03*
Y02097D03*
X02203Y00958D03*
X0299D03*
X0299Y02438D03*
G54D167*
X02043Y04157D03*
Y04057D03*
X01457Y04153D03*
Y04053D03*
G54D168*
X02043Y04257D03*
X01457Y04253D03*
G54D169*
X069Y04093D03*
X06569D03*
G54D170*
X00285Y04152D03*
Y00368D03*
G54D171*
X04039Y03784D03*
X02494Y02661D03*
X02692Y02721D03*
X02511Y00405D03*
X0261Y00279D03*
X02578D03*
X0298Y00409D03*
X02821Y00407D03*
X02748Y00282D03*
X02469Y0041D03*
X02905Y00279D03*
X02878Y00249D03*
X02692Y00795D03*
X02665D03*
X02854Y00405D03*
X02779Y00279D03*
X02665Y00405D03*
X02704D03*
X0235D03*
X02389D03*
X02937Y00279D03*
X02957Y00251D03*
X03019Y00405D03*
X0274Y00976D03*
X02767D03*
X02732Y00795D03*
X02681Y00976D03*
X02708D03*
X02447Y00242D03*
X02413Y00279D03*
X02444D03*
X02606Y00931D03*
X02625Y00795D03*
X02598D03*
X02636Y00247D03*
X02799Y00251D03*
X02826Y00976D03*
X02799D03*
X02649D03*
X02622D03*
X02759Y00795D03*
X02799D03*
X02826D03*
X02862D03*
X02893D03*
X02409Y01088D03*
X02311Y0109D03*
X02508Y00931D03*
X02409Y00932D03*
X02724Y01093D03*
X02784Y01094D03*
X02842Y01095D03*
X02546Y00244D03*
X03097Y00251D03*
X02475Y02291D03*
X0233Y02215D03*
X01798Y01304D03*
X02606Y01091D03*
X03554Y01841D03*
X03719Y01996D03*
X03894Y01566D03*
X03379Y01386D03*
X01721Y0189D03*
X01671Y01792D03*
X01674Y01989D03*
X02508Y0109D03*
X03413Y01573D03*
X0167Y01595D03*
X01754Y02126D03*
X02409Y02579D03*
X02586Y02569D03*
X03197Y01714D03*
X03439Y0187D03*
X03298Y01971D03*
X02985Y02287D03*
X02702Y02289D03*
X02821Y02601D03*
X01718Y01792D03*
X02881Y02566D03*
X03732Y01418D03*
X03554Y01891D03*
X02253Y02279D03*
X02272Y02463D03*
X01719Y01536D03*
X02311Y00934D03*
X03571Y02033D03*
X03554Y01991D03*
X02942Y02286D03*
X02841Y02263D03*
X02394Y0272D03*
X01567Y01285D03*
X01675Y01891D03*
X01568Y02067D03*
X02783Y02429D03*
X03719Y01921D03*
X03773Y01666D03*
X02599Y02436D03*
X02494Y02696D03*
X02894Y02431D03*
X02665Y01092D03*
X02475Y02456D03*
X03414Y01805D03*
X03404Y01363D03*
X02579Y02281D03*
X02685Y02311D03*
X0359Y01662D03*
X02404Y02412D03*
X02803Y02307D03*
X01716Y01399D03*
X01721Y01989D03*
X01619Y02121D03*
X03549Y01413D03*
X02488Y02413D03*
X02726Y02293D03*
X01822Y01674D03*
X0167Y01694D03*
X01884Y02071D03*
X02901Y01095D03*
X0292Y02428D03*
X01893Y01693D03*
X03594Y01514D03*
X0245Y02282D03*
X02409Y02314D03*
X02958Y02621D03*
X03406Y01461D03*
X0341Y01713D03*
X03252Y01661D03*
X02933Y00953D03*
X02871Y02297D03*
X02685Y02568D03*
X03571Y02058D03*
X03804Y0184D03*
X01879Y01811D03*
X03554Y01941D03*
X03392Y01871D03*
X03407Y01411D03*
X02575Y02412D03*
X02499Y02236D03*
X02409Y02283D03*
X02783Y02568D03*
X02948Y02456D03*
X03549Y01441D03*
X03718Y01713D03*
X02624Y02461D03*
X01897Y01516D03*
X03834Y01481D03*
X03864Y01511D03*
X03924Y01536D03*
X03719Y01766D03*
X03329Y01826D03*
X02645Y02274D03*
X02665Y02291D03*
X01721Y01694D03*
X01671Y01399D03*
X02581Y02308D03*
X03803Y01691D03*
X03224Y01661D03*
X02252Y02613D03*
X01718Y01497D03*
X01714Y01595D03*
X01671Y01497D03*
X02321Y02586D03*
X03379Y01336D03*
X01797Y00355D03*
X02034Y00246D03*
X01916Y00244D03*
X02309Y00246D03*
X0333Y03301D03*
X0412Y03594D03*
X01393Y01816D03*
X0099Y00687D03*
X04794Y02808D03*
X03183Y03135D03*
X03277Y02963D03*
X03197Y0297D03*
X03491Y03103D03*
X03188Y03187D03*
X0323Y03235D03*
X03358Y03448D03*
X03068Y03395D03*
X02419Y02788D03*
X02146Y02753D03*
X03275Y03141D03*
X03056Y01811D03*
X02413Y03295D03*
X02254Y03536D03*
X02579Y03486D03*
X02389Y03481D03*
X02321Y03361D03*
X02434Y03546D03*
X02634Y03406D03*
X02631Y02876D03*
X02591Y03186D03*
X0259Y03288D03*
X00996Y02256D03*
X02004Y01336D03*
X02028Y01361D03*
X02549Y01755D03*
X02418Y03118D03*
X02414Y03199D03*
X02462Y03172D03*
X02473Y0298D03*
X02146Y04103D03*
X02253Y04086D03*
X01408Y0398D03*
X01345Y04175D03*
X00996Y01187D03*
X00988Y01717D03*
X00937Y02317D03*
X02353Y04017D03*
X01726Y04329D03*
X01788D03*
X04477Y03135D03*
X04064Y02722D03*
X06628Y01372D03*
X04039Y02406D03*
X06974Y01939D03*
X04134Y01651D03*
X03994Y01551D03*
X04134Y01751D03*
X04151Y01623D03*
X03968Y01671D03*
X03969Y01552D03*
X03944Y01816D03*
X04131Y01686D03*
X04179Y01601D03*
X04034Y01546D03*
X03996Y01711D03*
X04064Y01796D03*
Y01511D03*
X03263Y03303D03*
X0396Y02724D03*
X01569Y04171D03*
X02076Y00255D03*
Y00287D03*
X02112D03*
X02151D03*
X02112Y00255D03*
X02151D03*
X01832D03*
X01852D03*
X01872D03*
X01832Y00287D03*
X01852D03*
X01872D03*
X06253Y02909D03*
X06647Y03129D03*
X05267Y04088D03*
X04339Y02725D03*
X04503Y02789D03*
X02231Y02584D03*
X05994Y03552D03*
X04049Y03665D03*
X03829Y03806D03*
X05577Y02214D03*
X02694Y01481D03*
X02384Y01941D03*
X0383Y03762D03*
X06334Y03266D03*
X03744Y03261D03*
X03395Y04222D03*
X04272Y03135D03*
X05634Y02236D03*
X02626Y0177D03*
X06304Y03121D03*
X03939D03*
X02139Y03738D03*
X04208Y03135D03*
X02604Y01734D03*
X06626Y03032D03*
X04152Y03135D03*
X02299Y01916D03*
X02724Y03521D03*
X01248Y02D03*
X02579Y0179D03*
X04068Y03135D03*
X02674Y03501D03*
X04234Y02725D03*
X06456Y03009D03*
X01691Y04079D03*
X03642Y00636D03*
X02259Y03261D03*
X03374Y03273D03*
X03368Y0305D03*
X06476Y03231D03*
X04333Y03135D03*
X01557Y04229D03*
X06282Y03226D03*
X03806Y03235D03*
X01261Y02482D03*
X04114Y03135D03*
X06648Y03341D03*
X02888Y04221D03*
X0337Y02888D03*
X02258Y03741D03*
X01749Y0411D03*
X0257Y04283D03*
X01459Y03147D03*
X0144Y03557D03*
X01903Y04018D03*
X0229Y04217D03*
X0388Y03109D03*
X03623Y02587D03*
X03622Y03486D03*
X03491Y03297D03*
X03542Y03319D03*
X03344Y02996D03*
X03744Y03342D03*
X03653Y03293D03*
X03394Y03447D03*
X03436Y03457D03*
X03717Y03072D03*
X02799Y03616D03*
X03589Y01711D03*
X05733Y03556D03*
X05676Y03546D03*
X03603Y00682D03*
X02478Y00937D03*
X06548Y01531D03*
X06602Y01612D03*
Y01672D03*
Y01722D03*
X06601Y01777D03*
X06685Y01828D03*
X06699Y01881D03*
X06949Y02095D03*
X06607Y02176D03*
X06395Y02111D03*
X06048Y02171D03*
X06004Y02434D03*
X06274Y02391D03*
X06398Y02453D03*
X06397Y02501D03*
X06396Y02556D03*
X06397Y0261D03*
X06398Y02657D03*
X06372Y02909D03*
X0491Y04203D03*
X04387Y04206D03*
X03777Y04023D03*
X04085Y03892D03*
X04194Y03884D03*
X04431Y03135D03*
X0286Y03787D03*
X02724Y03729D03*
X03531Y0366D03*
X03269Y03788D03*
X01242Y01472D03*
X01256Y00942D03*
X00654Y0079D03*
X00655Y01028D03*
X00654Y01314D03*
X00653Y01551D03*
X00654Y01839D03*
Y02073D03*
Y02365D03*
X00653Y02593D03*
X02206Y01298D03*
X02205Y032D03*
X02502Y01316D03*
X02525Y02463D03*
X03342Y02263D03*
X03498Y02341D03*
X02429Y02621D03*
X01004Y00906D03*
X02446Y01437D03*
X01008Y0143D03*
X02409Y01967D03*
X01009Y01956D03*
X0102Y02481D03*
X02643Y01616D03*
X02666Y0164D03*
X01884Y03601D03*
X01754Y03661D03*
X03424Y03636D03*
X01549Y03621D03*
X03239Y03596D03*
X01574D03*
X03539Y03806D03*
X03219D03*
X02722Y03786D03*
X02139Y03611D03*
X02084Y03896D03*
X02083Y01411D03*
X02059Y01386D03*
Y03871D03*
X02029Y03836D03*
X01294Y04256D03*
X02004Y03816D03*
X02234Y03506D03*
X03529Y03481D03*
X05274Y03511D03*
X06284Y02501D03*
X02679Y03661D03*
X02774Y03566D03*
X02993Y03751D03*
X03699D03*
X03014Y03831D03*
X03699Y03836D03*
X04254Y03776D03*
X02894Y01561D03*
X02919Y01536D03*
X02274Y01506D03*
X02719Y01591D03*
X03724Y01675D03*
X06844Y01661D03*
X06424Y02181D03*
X06309Y03199D03*
X06339Y03151D03*
X04754Y04115D03*
X01779Y04156D03*
X03504Y04086D03*
X03854Y03151D03*
X03829Y03176D03*
X03799Y03201D03*
X06439Y03191D03*
X06354Y03331D03*
X06444Y03291D03*
X03302Y03344D03*
X06409Y03371D03*
X06447Y03396D03*
X06479Y03426D03*
X06509Y03456D03*
X03469D03*
X01849Y03701D03*
X06294D03*
G54D172*
X02531Y03853D03*
Y0283D03*
X00149D03*
Y03853D03*
M02*